%FSTAX25Y25*%
%MOIN*%
%SFA1B1*%

%IPPOS*%
%ADD108C,0.120000*%
%ADD120C,0.075000*%
%ADD121R,0.059060X0.059060*%
%ADD126C,0.016000*%
%LNtimecard-dc-beta-v1-1*%
%LPD*%
G36*
X0707874Y0050906D02*
X0311484D01*
Y0022539*
X0229484*
Y0031406*
X0226284Y0034606*
X0223484*
X0220284Y0031406*
Y0022539*
X0178184*
Y0046906*
X0173584Y0051506*
X0166384*
X0161884Y0047006*
Y0031299*
X0132184*
Y0051206*
X0058184*
Y0018806*
X0000784*
Y0435406*
X0001992Y0436614*
X0707874*
Y0050906*
G37*
%LNtimecard-dc-beta-v1-2*%
%LPC*%
G36*
X0125Y0431749D02*
X0124376Y0431625D01*
X0123846Y0431272*
X0123493Y0430742*
X0123369Y0430118*
X0123493Y0429494*
X0123846Y0428965*
X0124376Y0428611*
X0125Y0428487*
X0125624Y0428611*
X0126154Y0428965*
X0126507Y0429494*
X0126631Y0430118*
X0126507Y0430742*
X0126154Y0431272*
X0125624Y0431625*
X0125Y0431749*
G37*
G36*
X0104331D02*
X0103706Y0431625D01*
X0103177Y0431272*
X0102823Y0430742*
X0102699Y0430118*
X0102823Y0429494*
X0103177Y0428965*
X0103706Y0428611*
X0104331Y0428487*
X0104955Y0428611*
X0105484Y0428965*
X0105838Y0429494*
X0105962Y0430118*
X0105838Y0430742*
X0105484Y0431272*
X0104955Y0431625*
X0104331Y0431749*
G37*
G36*
X0084646D02*
X0084021Y0431625D01*
X0083492Y0431272*
X0083139Y0430742*
X0083014Y0430118*
X0083139Y0429494*
X0083492Y0428965*
X0084021Y0428611*
X0084646Y0428487*
X008527Y0428611*
X0085799Y0428965*
X0086153Y0429494*
X0086277Y0430118*
X0086153Y0430742*
X0085799Y0431272*
X008527Y0431625*
X0084646Y0431749*
G37*
G36*
X0064961D02*
X0064336Y0431625D01*
X0063807Y0431272*
X0063454Y0430742*
X0063329Y0430118*
X0063454Y0429494*
X0063807Y0428965*
X0064336Y0428611*
X0064961Y0428487*
X0065585Y0428611*
X0066114Y0428965*
X0066468Y0429494*
X0066592Y0430118*
X0066468Y0430742*
X0066114Y0431272*
X0065585Y0431625*
X0064961Y0431749*
G37*
G36*
X0543622Y0429966D02*
X0542642Y0429837D01*
X0541729Y0429459*
X0540946Y0428858*
X0540344Y0428074*
X0539966Y0427161*
X0539837Y0426181*
X0539966Y0425201*
X0540344Y0424289*
X0540946Y0423505*
X0541729Y0422903*
X0542642Y0422525*
X0543622Y0422396*
X0544602Y0422525*
X0545515Y0422903*
X0546299Y0423505*
X05469Y0424289*
X0547278Y0425201*
X0547407Y0426181*
X0547278Y0427161*
X05469Y0428074*
X0546299Y0428858*
X0545515Y0429459*
X0544602Y0429837*
X0543622Y0429966*
G37*
G36*
X0533622D02*
X0532642Y0429837D01*
X053173Y0429459*
X0530946Y0428858*
X0530344Y0428074*
X0529966Y0427161*
X0529837Y0426181*
X0529966Y0425201*
X0530344Y0424289*
X0530946Y0423505*
X053173Y0422903*
X0532642Y0422525*
X0533622Y0422396*
X0534602Y0422525*
X0535515Y0422903*
X0536299Y0423505*
X05369Y0424289*
X0537278Y0425201*
X0537407Y0426181*
X0537278Y0427161*
X05369Y0428074*
X0536299Y0428858*
X0535515Y0429459*
X0534602Y0429837*
X0533622Y0429966*
G37*
G36*
X0523622D02*
X0522642Y0429837D01*
X052173Y0429459*
X0520946Y0428858*
X0520344Y0428074*
X0519966Y0427161*
X0519837Y0426181*
X0519966Y0425201*
X0520344Y0424289*
X0520946Y0423505*
X052173Y0422903*
X0522642Y0422525*
X0523622Y0422396*
X0524602Y0422525*
X0525515Y0422903*
X0526299Y0423505*
X05269Y0424289*
X0527278Y0425201*
X0527407Y0426181*
X0527278Y0427161*
X05269Y0428074*
X0526299Y0428858*
X0525515Y0429459*
X0524602Y0429837*
X0523622Y0429966*
G37*
G36*
X0505905Y041797D02*
X0505281Y0417846D01*
X0504752Y0417492*
X0504398Y0416963*
X0504274Y0416339*
X0504398Y0415714*
X0504752Y0415185*
X0505281Y0414831*
X0505905Y0414707*
X050653Y0414831*
X0507059Y0415185*
X0507413Y0415714*
X0507537Y0416339*
X0507413Y0416963*
X0507059Y0417492*
X050653Y0417846*
X0505905Y041797*
G37*
G36*
X0482313Y0430499D02*
X0480618Y0430365D01*
X0478965Y0429969*
X0477395Y0429318*
X0475945Y042843*
X0474653Y0427326*
X0473549Y0426033*
X047266Y0424584*
X047201Y0423013*
X0471613Y042136*
X047148Y0419665*
X0471613Y0417971*
X047201Y0416318*
X047266Y0414747*
X0473549Y0413298*
X0474653Y0412005*
X0475945Y0410901*
X0477395Y0410013*
X0478965Y0409362*
X0480618Y0408965*
X0482313Y0408832*
X0484008Y0408965*
X0485661Y0409362*
X0487231Y0410013*
X0488681Y0410901*
X0489973Y0412005*
X0491077Y0413298*
X0491966Y0414747*
X0492616Y0416318*
X0493013Y0417971*
X0493146Y0419665*
X0493013Y042136*
X0492616Y0423013*
X0491966Y0424584*
X0491077Y0426033*
X0489973Y0427326*
X0488681Y042843*
X0487231Y0429318*
X0485661Y0429969*
X0484008Y0430365*
X0482313Y0430499*
G37*
G36*
X0244124D02*
X0242429Y0430365D01*
X0240776Y0429969*
X0239206Y0429318*
X0237756Y042843*
X0236464Y0427326*
X023536Y0426033*
X0234471Y0424584*
X0233821Y0423013*
X0233424Y042136*
X0233291Y0419665*
X0233424Y0417971*
X0233821Y0416318*
X0234471Y0414747*
X023536Y0413298*
X0236464Y0412005*
X0237756Y0410901*
X0239206Y0410013*
X0240776Y0409362*
X0242429Y0408965*
X0244124Y0408832*
X0245819Y0408965*
X0247472Y0409362*
X0249042Y0410013*
X0250492Y0410901*
X0251784Y0412005*
X0252888Y0413298*
X0253777Y0414747*
X0254427Y0416318*
X0254824Y0417971*
X0254957Y0419665*
X0254824Y042136*
X0254427Y0423013*
X0253777Y0424584*
X0252888Y0426033*
X0251784Y0427326*
X0250492Y042843*
X0249042Y0429318*
X0247472Y0429969*
X0245819Y0430365*
X0244124Y0430499*
G37*
G36*
X0181102Y041108D02*
X0180478Y0410956D01*
X0179949Y0410602*
X0179595Y0410073*
X0179471Y0409449*
X0179595Y0408824*
X0179949Y0408295*
X0180478Y0407942*
X0181102Y0407818*
X0181727Y0407942*
X0182256Y0408295*
X0182609Y0408824*
X0182734Y0409449*
X0182609Y0410073*
X0182256Y0410602*
X0181727Y0410956*
X0181102Y041108*
G37*
G36*
X0173228D02*
X0172604Y0410956D01*
X0172075Y0410602*
X0171721Y0410073*
X0171597Y0409449*
X0171721Y0408824*
X0172075Y0408295*
X0172604Y0407942*
X0173228Y0407818*
X0173853Y0407942*
X0174382Y0408295*
X0174735Y0408824*
X017486Y0409449*
X0174735Y0410073*
X0174382Y0410602*
X0173853Y0410956*
X0173228Y041108*
G37*
G36*
X019661Y0412745D02*
X019554Y0412604D01*
X0194543Y0412191*
X0193687Y0411534*
X019303Y0410677*
X0192616Y040968*
X0192476Y040861*
X0192616Y040754*
X019303Y0406543*
X0193687Y0405687*
X0194543Y040503*
X019554Y0404616*
X019661Y0404476*
X019768Y0404616*
X0198678Y040503*
X0199534Y0405687*
X0200191Y0406543*
X0200604Y040754*
X0200745Y040861*
X0200604Y040968*
X0200191Y0410677*
X0199534Y0411534*
X0198678Y0412191*
X019768Y0412604*
X019661Y0412745*
G37*
G36*
X016661D02*
X016554Y0412604D01*
X0164543Y0412191*
X0163687Y0411534*
X016303Y0410677*
X0162617Y040968*
X0162476Y040861*
X0162617Y040754*
X016303Y0406543*
X0163687Y0405687*
X0164543Y040503*
X016554Y0404616*
X016661Y0404476*
X016768Y0404616*
X0168677Y040503*
X0169534Y0405687*
X0170191Y0406543*
X0170604Y040754*
X0170745Y040861*
X0170604Y040968*
X0170191Y0410677*
X0169534Y0411534*
X0168677Y0412191*
X016768Y0412604*
X016661Y0412745*
G37*
G36*
X0028543Y0428547D02*
X0026456Y0428383D01*
X0024421Y0427894*
X0022487Y0427093*
X0020702Y0425999*
X001911Y042464*
X001775Y0423048*
X0016656Y0421263*
X0015855Y0419329*
X0015366Y0417293*
X0015202Y0415206*
X0015366Y0413119*
X0015855Y0411084*
X0016656Y040915*
X001775Y0407365*
X001911Y0405773*
X0020702Y0404413*
X0022487Y0403319*
X0024421Y0402518*
X0026456Y0402029*
X0028543Y0401865*
X003063Y0402029*
X0032666Y0402518*
X00346Y0403319*
X0036385Y0404413*
X0037977Y0405773*
X0039336Y0407365*
X004043Y040915*
X0041232Y0411084*
X004172Y0413119*
X0041884Y0415206*
X004172Y0417293*
X0041232Y0419329*
X004043Y0421263*
X0039336Y0423048*
X0037977Y042464*
X0036385Y0425999*
X00346Y0427093*
X0032666Y0427894*
X003063Y0428383*
X0028543Y0428547*
G37*
G36*
X0124397Y0403225D02*
X0123773Y0403101D01*
X0123243Y0402747*
X012289Y0402218*
X0122766Y0401594*
X012289Y0400969*
X0123243Y040044*
X0123773Y0400086*
X0124397Y0399962*
X0125021Y0400086*
X012555Y040044*
X0125904Y0400969*
X0126028Y0401594*
X0125904Y0402218*
X012555Y0402747*
X0125021Y0403101*
X0124397Y0403225*
G37*
G36*
X010423Y0403092D02*
X0103606Y0402968D01*
X0103077Y0402614*
X0102723Y0402085*
X0102599Y040146*
X0102723Y0400836*
X0103077Y0400307*
X0103606Y0399953*
X010423Y0399829*
X0104855Y0399953*
X0105384Y0400307*
X0105737Y0400836*
X0105861Y040146*
X0105737Y0402085*
X0105384Y0402614*
X0104855Y0402968*
X010423Y0403092*
G37*
G36*
X0084064Y0402958D02*
X0083439Y0402834D01*
X008291Y0402481*
X0082556Y0401951*
X0082432Y0401327*
X0082556Y0400703*
X008291Y0400174*
X0083439Y039982*
X0084064Y0399696*
X0084688Y039982*
X0085217Y0400174*
X0085571Y0400703*
X0085695Y0401327*
X0085571Y0401951*
X0085217Y0402481*
X0084688Y0402834*
X0084064Y0402958*
G37*
G36*
X0063897Y0402925D02*
X0063273Y0402801D01*
X0062743Y0402447*
X006239Y0401918*
X0062265Y0401294*
X006239Y0400669*
X0062743Y040014*
X0063273Y0399786*
X0063897Y0399662*
X0064521Y0399786*
X006505Y040014*
X0065404Y0400669*
X0065528Y0401294*
X0065404Y0401918*
X006505Y0402447*
X0064521Y0402801*
X0063897Y0402925*
G37*
G36*
X021752Y036482D02*
X0216895Y0364696D01*
X0216366Y0364342*
X0216013Y0363813*
X0215888Y0363189*
X0216013Y0362565*
X0216366Y0362035*
X0216895Y0361682*
X021752Y0361558*
X0218144Y0361682*
X0218673Y0362035*
X0219027Y0362565*
X0219151Y0363189*
X0219027Y0363813*
X0218673Y0364342*
X0218144Y0364696*
X021752Y036482*
G37*
G36*
X0199803D02*
X0199179Y0364696D01*
X019865Y0364342*
X0198296Y0363813*
X0198172Y0363189*
X0198296Y0362565*
X019865Y0362035*
X0199179Y0361682*
X0199803Y0361558*
X0200427Y0361682*
X0200957Y0362035*
X020131Y0362565*
X0201434Y0363189*
X020131Y0363813*
X0200957Y0364342*
X0200427Y0364696*
X0199803Y036482*
G37*
G36*
X0181794Y0364528D02*
X018117Y0364404D01*
X0180641Y036405*
X0180287Y0363521*
X0180163Y0362897*
X0180287Y0362273*
X0180641Y0361743*
X018117Y036139*
X0181794Y0361265*
X0182419Y036139*
X0182948Y0361743*
X0183302Y0362273*
X0183426Y0362897*
X0183302Y0363521*
X0182948Y036405*
X0182419Y0364404*
X0181794Y0364528*
G37*
G36*
X0163992Y0364442D02*
X0163368Y0364318D01*
X0162839Y0363965*
X0162485Y0363435*
X0162361Y0362811*
X0162485Y0362187*
X0162839Y0361658*
X0163368Y0361304*
X0163992Y036118*
X0164616Y0361304*
X0165146Y0361658*
X0165499Y0362187*
X0165623Y0362811*
X0165499Y0363435*
X0165146Y0363965*
X0164616Y0364318*
X0163992Y0364442*
G37*
G36*
X0238189Y0363836D02*
X0237565Y0363712D01*
X0237035Y0363358*
X0236682Y0362829*
X0236558Y0362205*
X0236682Y036158*
X0237035Y0361051*
X0237565Y0360698*
X0238189Y0360573*
X0238813Y0360698*
X0239342Y0361051*
X0239696Y036158*
X023982Y0362205*
X0239696Y0362829*
X0239342Y0363358*
X0238813Y0363712*
X0238189Y0363836*
G37*
G36*
X025503Y0360609D02*
X0254134Y0360431D01*
X0253374Y0359923*
X0252867Y0359164*
X0252689Y0358268*
X0252867Y0357372*
X0253374Y0356612*
X0254134Y0356105*
X025503Y0355927*
X0255925Y0356105*
X0256685Y0356612*
X0257192Y0357372*
X0257371Y0358268*
X0257192Y0359164*
X0256685Y0359923*
X0255925Y0360431*
X025503Y0360609*
G37*
G36*
X0271654Y0355962D02*
X0271029Y0355838D01*
X02705Y0355484*
X0270146Y0354955*
X0270022Y0354331*
X0270146Y0353706*
X02705Y0353177*
X0271029Y0352823*
X0271654Y0352699*
X0272278Y0352823*
X0272807Y0353177*
X0273161Y0353706*
X0273285Y0354331*
X0273161Y0354955*
X0272807Y0355484*
X0272278Y0355838*
X0271654Y0355962*
G37*
G36*
X0238189D02*
X0237565Y0355838D01*
X0237035Y0355484*
X0236682Y0354955*
X0236558Y0354331*
X0236682Y0353706*
X0237035Y0353177*
X0237565Y0352823*
X0238189Y0352699*
X0238813Y0352823*
X0239342Y0353177*
X0239696Y0353706*
X023982Y0354331*
X0239696Y0354955*
X0239342Y0355484*
X0238813Y0355838*
X0238189Y0355962*
G37*
G36*
X0271654Y0348088D02*
X0271029Y0347964D01*
X02705Y034761*
X0270146Y0347081*
X0270022Y0346457*
X0270146Y0345832*
X02705Y0345303*
X0271029Y034495*
X0271654Y0344825*
X0272278Y034495*
X0272807Y0345303*
X0273161Y0345832*
X0273285Y0346457*
X0273161Y0347081*
X0272807Y034761*
X0272278Y0347964*
X0271654Y0348088*
G37*
G36*
X0238189D02*
X0237565Y0347964D01*
X0237035Y034761*
X0236682Y0347081*
X0236558Y0346457*
X0236682Y0345832*
X0237035Y0345303*
X0237565Y034495*
X0238189Y0344825*
X0238813Y034495*
X0239342Y0345303*
X0239696Y0345832*
X023982Y0346457*
X0239696Y0347081*
X0239342Y034761*
X0238813Y0347964*
X0238189Y0348088*
G37*
G36*
X025503Y0344861D02*
X0254134Y0344683D01*
X0253374Y0344175*
X0252867Y0343416*
X0252689Y034252*
X0252867Y0341624*
X0253374Y0340864*
X0254134Y0340357*
X025503Y0340179*
X0255925Y0340357*
X0256685Y0340864*
X0257192Y0341624*
X0257371Y034252*
X0257192Y0343416*
X0256685Y0344175*
X0255925Y0344683*
X025503Y0344861*
G37*
G36*
X0304134Y0341198D02*
X030351Y0341074D01*
X030298Y0340721*
X0302627Y0340191*
X0302502Y0339567*
X0302627Y0338943*
X030298Y0338413*
X030351Y033806*
X0304134Y0337936*
X0304758Y033806*
X0305287Y0338413*
X0305641Y0338943*
X0305765Y0339567*
X0305641Y0340191*
X0305287Y0340721*
X0304758Y0341074*
X0304134Y0341198*
G37*
G36*
X0276772Y032171D02*
X0276147Y0321586D01*
X0275618Y0321232*
X0275265Y0320703*
X027514Y0320079*
X0275265Y0319454*
X0275618Y0318925*
X0276147Y0318572*
X0276772Y0318447*
X0277396Y0318572*
X0277925Y0318925*
X0278279Y0319454*
X0278403Y0320079*
X0278279Y0320703*
X0277925Y0321232*
X0277396Y0321586*
X0276772Y032171*
G37*
G36*
X0667108Y0317614D02*
X0666484Y031749D01*
X0666124Y0317249*
X0665764Y031749*
X066514Y0317614*
X0664515Y031749*
X0664155Y0317249*
X0663796Y031749*
X0663171Y0317614*
X0662547Y031749*
X0662018Y0317136*
X0661664Y0316607*
X066154Y0315982*
X0661664Y0315358*
X0661905Y0314998*
X0661664Y0314638*
X066154Y0314014*
X0661664Y0313389*
X0662018Y031286*
X0662547Y0312507*
X0663171Y0312382*
X0663796Y0312507*
X0664155Y0312747*
X0664515Y0312507*
X066514Y0312382*
X0665764Y0312507*
X0666124Y0312747*
X0666484Y0312507*
X0667108Y0312382*
X0667733Y0312507*
X0668262Y031286*
X0668615Y0313389*
X066874Y0314014*
X0668615Y0314638*
X0668375Y0314998*
X0668615Y0315358*
X066874Y0315982*
X0668615Y0316607*
X0668262Y0317136*
X0667733Y031749*
X0667108Y0317614*
G37*
G36*
X0482313Y0328136D02*
X0480618Y0328003D01*
X0478965Y0327606*
X0477395Y0326956*
X0475945Y0326067*
X0474653Y0324963*
X0473549Y0323671*
X047266Y0322221*
X047201Y0320651*
X0471613Y0318998*
X047148Y0317303*
X0471613Y0315608*
X047201Y0313955*
X047266Y0312385*
X0473549Y0310935*
X0474653Y0309643*
X0475945Y0308539*
X0477395Y030765*
X0478965Y0307*
X0480618Y0306603*
X0482313Y030647*
X0484008Y0306603*
X0485661Y0307*
X0487231Y030765*
X0488681Y0308539*
X0489973Y0309643*
X0491077Y0310935*
X0491966Y0312385*
X0492616Y0313955*
X0493013Y0315608*
X0493146Y0317303*
X0493013Y0318998*
X0492616Y0320651*
X0491966Y0322221*
X0491077Y0323671*
X0489973Y0324963*
X0488681Y0326067*
X0487231Y0326956*
X0485661Y0327606*
X0484008Y0328003*
X0482313Y0328136*
G37*
G36*
X0244124D02*
X0242429Y0328003D01*
X0240776Y0327606*
X0239206Y0326956*
X0237756Y0326067*
X0236464Y0324963*
X023536Y0323671*
X0234471Y0322221*
X0233821Y0320651*
X0233424Y0318998*
X0233291Y0317303*
X0233424Y0315608*
X0233821Y0313955*
X0234471Y0312385*
X023536Y0310935*
X0236464Y0309643*
X0237756Y0308539*
X0239206Y030765*
X0240776Y0307*
X0242429Y0306603*
X0244124Y030647*
X0245819Y0306603*
X0247472Y0307*
X0249042Y030765*
X0250492Y0308539*
X0251784Y0309643*
X0252888Y0310935*
X0253777Y0312385*
X0254427Y0313955*
X0254824Y0315608*
X0254957Y0317303*
X0254824Y0318998*
X0254427Y0320651*
X0253777Y0322221*
X0252888Y0323671*
X0251784Y0324963*
X0250492Y0326067*
X0249042Y0326956*
X0247472Y0327606*
X0245819Y0328003*
X0244124Y0328136*
G37*
G36*
X0350394Y0304749D02*
X0349769Y0304625D01*
X034924Y0304272*
X0348886Y0303742*
X0348762Y0303118*
X0348886Y0302494*
X034924Y0301965*
X0349769Y0301611*
X0350394Y0301487*
X0351018Y0301611*
X0351547Y0301965*
X0351901Y0302494*
X0352025Y0303118*
X0351901Y0303742*
X0351547Y0304272*
X0351018Y0304625*
X0350394Y0304749*
G37*
G36*
X0525591Y029986D02*
X0524966Y0299735D01*
X0524437Y0299382*
X0524083Y0298853*
X0523959Y0298228*
X0524083Y0297604*
X0524437Y0297075*
X0524966Y0296721*
X0525591Y0296597*
X0526215Y0296721*
X0526744Y0297075*
X0527098Y0297604*
X0527222Y0298228*
X0527098Y0298853*
X0526744Y0299382*
X0526215Y0299735*
X0525591Y029986*
G37*
G36*
X05Y0296907D02*
X0499376Y0296783D01*
X0498846Y0296429*
X0498493Y02959*
X0498369Y0295276*
X0498493Y0294651*
X0498846Y0294122*
X0499376Y0293768*
X05Y0293644*
X0500624Y0293768*
X0501154Y0294122*
X0501507Y0294651*
X0501631Y0295276*
X0501507Y02959*
X0501154Y0296429*
X0500624Y0296783*
X05Y0296907*
G37*
G36*
X0320866Y0294938D02*
X0320242Y0294814D01*
X0319713Y0294461*
X0319359Y0293931*
X0319235Y0293307*
X0319359Y0292683*
X0319713Y0292154*
X0320242Y02918*
X0320866Y0291676*
X032149Y02918*
X032202Y0292154*
X0322373Y0292683*
X0322498Y0293307*
X0322373Y0293931*
X032202Y0294461*
X032149Y0294814*
X0320866Y0294938*
G37*
G36*
X0324803Y0294907D02*
X0324179Y0294783D01*
X032365Y0294429*
X0323296Y02939*
X0323172Y0293276*
X0323296Y0292651*
X032365Y0292122*
X0324179Y0291768*
X0324803Y0291644*
X0325427Y0291768*
X0325957Y0292122*
X032631Y0292651*
X0326434Y0293276*
X032631Y02939*
X0325957Y0294429*
X0325427Y0294783*
X0324803Y0294907*
G37*
G36*
X0329918Y0293994D02*
X0329294Y0293869D01*
X0328764Y0293516*
X0328411Y0292986*
X0328287Y0292362*
X0328411Y0291738*
X0328764Y0291209*
X0329294Y0290855*
X0329918Y0290731*
X0330542Y0290855*
X0331071Y0291209*
X0331425Y0291738*
X0331549Y0292362*
X0331425Y0292986*
X0331071Y0293516*
X0330542Y0293869*
X0329918Y0293994*
G37*
G36*
X030115Y0292938D02*
X0300525Y0292814D01*
X0299996Y0292461*
X0299642Y0291931*
X0299518Y0291307*
X0299642Y0290683*
X0299996Y0290154*
X0300525Y02898*
X030115Y0289676*
X0301774Y02898*
X0302303Y0290154*
X0302657Y0290683*
X0302781Y0291307*
X0302657Y0291931*
X0302303Y0292461*
X0301774Y0292814*
X030115Y0292938*
G37*
G36*
X0294341Y0292921D02*
X0293716Y0292796D01*
X0293187Y0292443*
X0292833Y0291914*
X0292709Y0291289*
X0292833Y0290665*
X0293187Y0290136*
X0293716Y0289782*
X0294341Y0289658*
X0294965Y0289782*
X0295494Y0290136*
X0295848Y0290665*
X0295972Y0291289*
X0295848Y0291914*
X0295494Y0292443*
X0294965Y0292796*
X0294341Y0292921*
G37*
G36*
X0564921Y0292025D02*
X0564297Y0291901D01*
X0563768Y0291547*
X0563414Y0291018*
X056329Y0290394*
X0563414Y0289769*
X0563768Y028924*
X0564297Y0288886*
X0564921Y0288762*
X0565546Y0288886*
X0566075Y028924*
X0566428Y0289769*
X0566553Y0290394*
X0566428Y0291018*
X0566075Y0291547*
X0565546Y0291901*
X0564921Y0292025*
G37*
G36*
X0371477Y0291248D02*
X0370852Y0291123D01*
X0370323Y029077*
X0369969Y029024*
X0369845Y0289616*
X0369969Y0288992*
X0370323Y0288463*
X0370852Y0288109*
X0371477Y0287985*
X0372101Y0288109*
X037263Y0288463*
X0372984Y0288992*
X0373108Y0289616*
X0372984Y029024*
X037263Y029077*
X0372101Y0291123*
X0371477Y0291248*
G37*
G36*
X0449803Y0291001D02*
X0449179Y0290877D01*
X044865Y0290524*
X0448296Y0289994*
X0448172Y028937*
X0448296Y0288746*
X044865Y0288216*
X0449179Y0287863*
X0449803Y0287739*
X0450427Y0287863*
X0450957Y0288216*
X045131Y0288746*
X0451435Y028937*
X045131Y0289994*
X0450957Y0290524*
X0450427Y0290877*
X0449803Y0291001*
G37*
G36*
X0570866Y0287064D02*
X0570242Y028694D01*
X0569713Y0286587*
X0569359Y0286057*
X0569235Y0285433*
X0569359Y0284809*
X0569713Y0284279*
X0570242Y0283926*
X0570866Y0283802*
X057149Y0283926*
X057202Y0284279*
X0572373Y0284809*
X0572498Y0285433*
X0572373Y0286057*
X057202Y0286587*
X057149Y028694*
X0570866Y0287064*
G37*
G36*
X0449803Y028608D02*
X0449179Y0285956D01*
X044865Y0285602*
X0448296Y0285073*
X0448172Y0284449*
X0448296Y0283824*
X044865Y0283295*
X0449179Y0282942*
X0449803Y0282818*
X0450427Y0282942*
X0450957Y0283295*
X045131Y0283824*
X0451435Y0284449*
X045131Y0285073*
X0450957Y0285602*
X0450427Y0285956*
X0449803Y028608*
G37*
G36*
X0249938Y0285158D02*
X0249313Y0285034D01*
X0248784Y028468*
X0248431Y0284151*
X0248306Y0283527*
X0248431Y0282902*
X0248784Y0282373*
X0249313Y028202*
X0249938Y0281895*
X0250562Y028202*
X0251091Y0282373*
X0251445Y0282902*
X0251569Y0283527*
X0251445Y0284151*
X0251091Y028468*
X0250562Y0285034*
X0249938Y0285158*
G37*
G36*
X0523228Y0283127D02*
X0522604Y0283003D01*
X0522075Y028265*
X0521721Y028212*
X0521597Y0281496*
X0521721Y0280872*
X0522075Y0280343*
X0522604Y0279989*
X0523228Y0279865*
X0523853Y0279989*
X0524382Y0280343*
X0524735Y0280872*
X052486Y0281496*
X0524735Y028212*
X0524382Y028265*
X0523853Y0283003*
X0523228Y0283127*
G37*
G36*
X0564961Y0282143D02*
X0564336Y0282019D01*
X0563807Y0281665*
X0563453Y0281136*
X0563329Y0280512*
X0563453Y0279888*
X0563807Y0279358*
X0564336Y0279005*
X0564961Y0278881*
X0565585Y0279005*
X0566114Y0279358*
X0566468Y0279888*
X0566592Y0280512*
X0566468Y0281136*
X0566114Y0281665*
X0565585Y0282019*
X0564961Y0282143*
G37*
G36*
X0362205Y0283127D02*
X036158Y0283003D01*
X0361051Y028265*
X0360698Y028212*
X0360573Y0281496*
X0360698Y0280872*
X0361051Y0280343*
X0361099Y0280311*
Y0279811*
X0361002Y0279746*
X0360648Y0279217*
X0360524Y0278592*
X0360648Y0277968*
X0361002Y0277439*
X0361531Y0277085*
X0362156Y0276961*
X036278Y0277085*
X0363309Y0277439*
X0363663Y0277968*
X0363787Y0278592*
X0363663Y0279217*
X0363309Y0279746*
X0363262Y0279778*
Y0280278*
X0363358Y0280343*
X0363712Y0280872*
X0363836Y0281496*
X0363712Y028212*
X0363358Y028265*
X0362829Y0283003*
X0362205Y0283127*
G37*
G36*
X0343504Y0277222D02*
X034288Y0277098D01*
X034235Y0276744*
X0341997Y0276215*
X0341873Y027559*
X0341997Y0274966*
X034235Y0274437*
X034288Y0274083*
X0343504Y0273959*
X0344128Y0274083*
X0344657Y0274437*
X0345011Y0274966*
X0345135Y027559*
X0345011Y0276215*
X0344657Y0276744*
X0344128Y0277098*
X0343504Y0277222*
G37*
G36*
X0564921Y0277183D02*
X0564297Y0277058D01*
X0563768Y0276705*
X0563414Y0276175*
X056329Y0275551*
X0563414Y0274927*
X0563768Y0274398*
X0564297Y0274044*
X0564921Y027392*
X0565546Y0274044*
X0566075Y0274398*
X0566428Y0274927*
X0566553Y0275551*
X0566428Y0276175*
X0566075Y0276705*
X0565546Y0277058*
X0564921Y0277183*
G37*
G36*
X0492913Y0276434D02*
X0492289Y027631D01*
X049176Y0275957*
X0491406Y0275427*
X0491282Y0274803*
X0491406Y0274179*
X049176Y027365*
X0492289Y0273296*
X0492913Y0273172*
X0493538Y0273296*
X0494067Y027365*
X0494421Y0274179*
X0494545Y0274803*
X0494421Y0275427*
X0494067Y0275957*
X0493538Y027631*
X0492913Y0276434*
G37*
G36*
X0312894Y0275352D02*
X0312269Y0275228D01*
X031174Y0274874*
X0311386Y0274345*
X0311262Y0273721*
X0311386Y0273096*
X031174Y0272567*
X0312269Y0272213*
X0312894Y0272089*
X0313518Y0272213*
X0314047Y0272567*
X0314401Y0273096*
X0314525Y0273721*
X0314401Y0274345*
X0314047Y0274874*
X0313518Y0275228*
X0312894Y0275352*
G37*
G36*
X0523228Y0275253D02*
X0522604Y0275129D01*
X0522075Y0274776*
X0521721Y0274246*
X0521597Y0273622*
X0521721Y0272998*
X0522075Y0272468*
X0522604Y0272115*
X0523228Y0271991*
X0523853Y0272115*
X0524382Y0272468*
X0524735Y0272998*
X052486Y0273622*
X0524735Y0274246*
X0524382Y0274776*
X0523853Y0275129*
X0523228Y0275253*
G37*
G36*
X024311Y0269379D02*
X0242486Y0269255D01*
X0241957Y0268902*
X0241603Y0268372*
X0241479Y0267748*
X0241603Y0267124*
X0241957Y0266595*
X0242486Y0266241*
X024311Y0266117*
X0243735Y0266241*
X0244264Y0266595*
X0244617Y0267124*
X0244742Y0267748*
X0244617Y0268372*
X0244264Y0268902*
X0243735Y0269255*
X024311Y0269379*
G37*
G36*
X0237205Y0269348D02*
X023658Y0269224D01*
X0236051Y026887*
X0235698Y0268341*
X0235573Y0267717*
X0235698Y0267092*
X0236051Y0266563*
X023658Y0266209*
X0237205Y0266085*
X0237829Y0266209*
X0238358Y0266563*
X0238712Y0267092*
X0238836Y0267717*
X0238712Y0268341*
X0238358Y026887*
X0237829Y0269224*
X0237205Y0269348*
G37*
G36*
X0247638Y0261868D02*
X0247013Y0261743D01*
X0246484Y026139*
X0246035*
X0245506Y0261743*
X0244882Y0261868*
X0244258Y0261743*
X0243728Y026139*
X0243375Y026086*
X024325Y0260236*
X0243375Y0259612*
X0243728Y0259083*
X0244258Y0258729*
X0244882Y0258605*
X0245506Y0258729*
X0246035Y0259083*
X0246484*
X0247013Y0258729*
X0247638Y0258605*
X0248262Y0258729*
X0248791Y0259083*
X0249145Y0259612*
X0249269Y0260236*
X0249145Y026086*
X0248791Y026139*
X0248262Y0261743*
X0247638Y0261868*
G37*
G36*
X0258858Y0264427D02*
X0258234Y0264302D01*
X0257705Y0263949*
X0257351Y026342*
X0257227Y0262795*
X0257351Y0262171*
X0257705Y0261642*
X0258234Y0261288*
X0258858Y0261164*
X0259483Y0261288*
X0260012Y0261642*
X0260365Y0262171*
X026049Y0262795*
X0260365Y026342*
X0260012Y0263949*
X0259483Y0264302*
X0258858Y0264427*
G37*
G36*
X0290059Y0262261D02*
X0289435Y0262137D01*
X0288906Y0261784*
X0288552Y0261254*
X0288428Y026063*
X0288552Y0260006*
X0288906Y0259476*
X0289435Y0259123*
X0290059Y0258999*
X0290683Y0259123*
X0291213Y0259476*
X0291566Y0260006*
X029169Y026063*
X0291566Y0261254*
X0291213Y0261784*
X0290683Y0262137*
X0290059Y0262261*
G37*
G36*
X0298031Y0262163D02*
X0297407Y0262039D01*
X0296878Y0261685*
X0296524Y0261156*
X02964Y0260531*
X0296524Y0259907*
X0296878Y0259378*
X0297407Y0259024*
X0298031Y02589*
X0298656Y0259024*
X0299185Y0259378*
X0299539Y0259907*
X0299663Y0260531*
X0299539Y0261156*
X0299185Y0261685*
X0298656Y0262039*
X0298031Y0262163*
G37*
G36*
X0228051Y0261671D02*
X0227427Y0261546D01*
X0226898Y0261193*
X0226544Y0260664*
X022642Y0260039*
X0226544Y0259415*
X0226898Y0258886*
X0227427Y0258532*
X0228051Y0258408*
X0228676Y0258532*
X0229205Y0258886*
X0229558Y0259415*
X0229682Y0260039*
X0229558Y0260664*
X0229205Y0261193*
X0228676Y0261546*
X0228051Y0261671*
G37*
G36*
X0293069Y0259614D02*
X0292444Y025949D01*
X0291915Y0259136*
X0291561Y0258607*
X0291437Y0257983*
X0291561Y0257358*
X0291915Y0256829*
X0292444Y0256475*
X0293069Y0256351*
X0293693Y0256475*
X0294222Y0256829*
X0294576Y0257358*
X02947Y0257983*
X0294576Y0258607*
X0294222Y0259136*
X0293693Y025949*
X0293069Y0259614*
G37*
G36*
X0430778Y0263054D02*
X042959Y0262897D01*
X0428483Y0262439*
X0427532Y026171*
X0426803Y0260759*
X0426345Y0259652*
X0426188Y0258465*
X0426345Y0257277*
X0426803Y025617*
X0427532Y025522*
X0428483Y025449*
X042959Y0254032*
X0430778Y0253875*
X0431965Y0254032*
X0433072Y025449*
X0434023Y025522*
X0434752Y025617*
X043521Y0257277*
X0435367Y0258465*
X043521Y0259652*
X0434752Y0260759*
X0434023Y026171*
X0433072Y0262439*
X0431965Y0262897*
X0430778Y0263054*
G37*
G36*
X0418966D02*
X0417779Y0262897D01*
X0416672Y0262439*
X0415721Y026171*
X0414992Y0260759*
X0414534Y0259652*
X0414377Y0258465*
X0414534Y0257277*
X0414992Y025617*
X0415721Y025522*
X0416672Y025449*
X0417779Y0254032*
X0418966Y0253875*
X0420154Y0254032*
X0421261Y025449*
X0422212Y025522*
X0422941Y025617*
X0423399Y0257277*
X0423556Y0258465*
X0423399Y0259652*
X0422941Y0260759*
X0422212Y026171*
X0421261Y0262439*
X0420154Y0262897*
X0418966Y0263054*
G37*
G36*
X0407156D02*
X0405968Y0262897D01*
X0404861Y0262439*
X040391Y026171*
X0403181Y0260759*
X0402723Y0259652*
X0402566Y0258465*
X0402723Y0257277*
X0403181Y025617*
X040391Y025522*
X0404861Y025449*
X0405968Y0254032*
X0407156Y0253875*
X0408343Y0254032*
X040945Y025449*
X0410401Y025522*
X041113Y025617*
X0411588Y0257277*
X0411745Y0258465*
X0411588Y0259652*
X041113Y0260759*
X0410401Y026171*
X040945Y0262439*
X0408343Y0262897*
X0407156Y0263054*
G37*
G36*
X011998Y0251828D02*
X0119356Y0251704D01*
X0118827Y025135*
X0118473Y0250821*
X0118349Y0250197*
X0118473Y0249573*
X0118827Y0249043*
X0119356Y024869*
X011998Y0248566*
X0120605Y024869*
X0121134Y0249043*
X0121487Y0249573*
X0121612Y0250197*
X0121487Y0250821*
X0121134Y025135*
X0120605Y0251704*
X011998Y0251828*
G37*
G36*
X0619685Y0250872D02*
X0618749Y0250686D01*
X0617955Y0250155*
X0617424Y0249362*
X0617238Y0248425*
X0617424Y0247489*
X0617955Y0246695*
X0618749Y0246164*
X0619685Y0245978*
X0620621Y0246164*
X0621415Y0246695*
X0621946Y0247489*
X0622132Y0248425*
X0621946Y0249362*
X0621415Y0250155*
X0620621Y0250686*
X0619685Y0250872*
G37*
G36*
X055873Y0252424D02*
X0557543Y0252268D01*
X0556436Y0251809*
X0555485Y025108*
X0554756Y0250129*
X0554297Y0249022*
X0554141Y0247835*
X0554297Y0246647*
X0554756Y024554*
X0555485Y024459*
X0556436Y024386*
X0557543Y0243402*
X055873Y0243245*
X0559918Y0243402*
X0561025Y024386*
X0561975Y024459*
X0562705Y024554*
X0563163Y0246647*
X0563319Y0247835*
X0563163Y0249022*
X0562705Y0250129*
X0561975Y025108*
X0561025Y0251809*
X0559918Y0252268*
X055873Y0252424*
G37*
G36*
X0299014Y0245759D02*
X029828Y0245613D01*
X0297657Y0245197*
X0297241Y0244574*
X0297095Y024384*
X0297241Y0243105*
X0297657Y0242482*
X029828Y0242066*
X0299014Y024192*
X0299749Y0242066*
X0300372Y0242482*
X0300788Y0243105*
X0300934Y024384*
X0300788Y0244574*
X0300372Y0245197*
X0299749Y0245613*
X0299014Y0245759*
G37*
G36*
X0220274D02*
X021954Y0245613D01*
X0218917Y0245197*
X0218501Y0244574*
X0218355Y024384*
X0218501Y0243105*
X0218917Y0242482*
X021954Y0242066*
X0220274Y024192*
X0221009Y0242066*
X0221632Y0242482*
X0222048Y0243105*
X0222194Y024384*
X0222048Y0244574*
X0221632Y0245197*
X0221009Y0245613*
X0220274Y0245759*
G37*
G36*
X0361755Y0255353D02*
X0360441Y0255224D01*
X0359177Y0254841*
X0358012Y0254218*
X0356991Y025338*
X0356153Y0252359*
X035553Y0251194*
X0355147Y024993*
X0355017Y0248616*
X0355147Y0247301*
X035553Y0246037*
X0356153Y0244872*
X0356991Y0243851*
X0358012Y0243013*
X0359177Y024239*
X0360441Y0242007*
X0361755Y0241878*
X036307Y0242007*
X0364334Y024239*
X0365499Y0243013*
X036652Y0243851*
X0367358Y0244872*
X0367981Y0246037*
X0368364Y0247301*
X0368493Y0248616*
X0368364Y024993*
X0367981Y0251194*
X0367358Y0252359*
X036652Y025338*
X0365499Y0254218*
X0364334Y0254841*
X036307Y0255224*
X0361755Y0255353*
G37*
G36*
X0165155D02*
X0163841Y0255224D01*
X0162577Y0254841*
X0161412Y0254218*
X0160391Y025338*
X0159553Y0252359*
X015893Y0251194*
X0158547Y024993*
X0158417Y0248616*
X0158547Y0247301*
X015893Y0246037*
X0159553Y0244872*
X0160391Y0243851*
X0161412Y0243013*
X0162577Y024239*
X0163841Y0242007*
X0165155Y0241878*
X016647Y0242007*
X0167734Y024239*
X0168899Y0243013*
X016992Y0243851*
X0170758Y0244872*
X017138Y0246037*
X0171764Y0247301*
X0171893Y0248616*
X0171764Y024993*
X017138Y0251194*
X0170758Y0252359*
X016992Y025338*
X0168899Y0254218*
X0167734Y0254841*
X016647Y0255224*
X0165155Y0255353*
G37*
G36*
X0019984Y0254537D02*
X001873Y0254414D01*
X0017523Y0254048*
X0016411Y0253453*
X0015437Y0252654*
X0014637Y0251679*
X0014043Y0250567*
X0013677Y0249361*
X0013553Y0248106*
X0013677Y0246852*
X0014043Y0245645*
X0014637Y0244533*
X0015437Y0243559*
X0016411Y0242759*
X0017523Y0242165*
X001873Y0241799*
X0019984Y0241675*
X0021239Y0241799*
X0022445Y0242165*
X0023557Y0242759*
X0024532Y0243559*
X0025331Y0244533*
X0025926Y0245645*
X0026292Y0246852*
X0026415Y0248106*
X0026292Y0249361*
X0025926Y0250567*
X0025331Y0251679*
X0024532Y0252654*
X0023557Y0253453*
X0022445Y0254048*
X0021239Y0254414*
X0019984Y0254537*
G37*
G36*
X0166437Y0235293D02*
X0165813Y0235169D01*
X0165284Y0234815*
X016493Y0234286*
X0164806Y0233661*
X016493Y0233037*
X0165284Y0232508*
X0165813Y0232154*
X0166437Y023203*
X0167061Y0232154*
X0167591Y0232508*
X0167944Y0233037*
X0168068Y0233661*
X0167944Y0234286*
X0167591Y0234815*
X0167061Y0235169*
X0166437Y0235293*
G37*
G36*
X0233563Y0230667D02*
X0232939Y0230543D01*
X0232651Y023035*
X0232283Y023023*
X0231916Y023035*
X0231628Y0230543*
X0231004Y0230667*
X023038Y0230543*
X022985Y0230189*
X0229497Y022966*
X0229373Y0229035*
X0229497Y0228411*
X022985Y0227882*
X023038Y0227528*
X0231004Y0227404*
X0231628Y0227528*
X0231916Y022772*
X0232283Y0227841*
X0232651Y022772*
X0232939Y0227528*
X0233563Y0227404*
X0234187Y0227528*
X0234717Y0227882*
X023507Y0228411*
X0235194Y0229035*
X023507Y022966*
X0234717Y0230189*
X0234187Y0230543*
X0233563Y0230667*
G37*
G36*
X0262598Y0230765D02*
X0261974Y0230641D01*
X0261445Y0230287*
X0261341Y0230131*
X0260739*
X0260701Y0230189*
X0260172Y0230543*
X0259547Y0230667*
X0258923Y0230543*
X0258394Y0230189*
X025804Y022966*
X0257991Y0229413*
X0257481*
X0257413Y0229758*
X0257059Y0230287*
X025653Y0230641*
X0255906Y0230765*
X0255281Y0230641*
X0254752Y0230287*
X0254679Y0230178*
X0254179*
X0254106Y0230287*
X0253577Y0230641*
X0252953Y0230765*
X0252328Y0230641*
X0251799Y0230287*
X0251446Y0229758*
X0251321Y0229134*
X0251446Y022851*
X0251799Y022798*
X0252328Y0227627*
X0252953Y0227502*
X0253577Y0227627*
X0254106Y022798*
X0254179Y0228089*
X0254679*
X0254752Y022798*
X0255281Y0227627*
X0255906Y0227502*
X025653Y0227627*
X0257059Y022798*
X0257413Y022851*
X0257462Y0228756*
X0257972*
X025804Y0228411*
X0258394Y0227882*
X0258923Y0227528*
X0259547Y0227404*
X0260172Y0227528*
X0260701Y0227882*
X0260805Y0228038*
X0261406*
X0261445Y022798*
X0261974Y0227627*
X0262598Y0227502*
X0263223Y0227627*
X0263752Y022798*
X0264106Y022851*
X026423Y0229134*
X0264106Y0229758*
X0263752Y0230287*
X0263223Y0230641*
X0262598Y0230765*
G37*
G36*
X0107283Y0232931D02*
X0106659Y0232806D01*
X010613Y0232453*
X0105776Y0231924*
X0105652Y0231299*
X0105776Y0230675*
X010613Y0230146*
X0106659Y0229792*
X0107283Y0229668*
X0107908Y0229792*
X0108437Y0230146*
X0108791Y0230675*
X0108915Y0231299*
X0108791Y0231924*
X0108437Y0232453*
X0107908Y0232806*
X0107283Y0232931*
G37*
G36*
X0164961Y0231651D02*
X0164336Y0231527D01*
X0163807Y0231173*
X0163453Y0230644*
X0163329Y023002*
X0163453Y0229395*
X0163807Y0228866*
X0164336Y0228513*
X0164961Y0228388*
X0165585Y0228513*
X0166114Y0228866*
X0166468Y0229395*
X0166592Y023002*
X0166468Y0230644*
X0166114Y0231173*
X0165585Y0231527*
X0164961Y0231651*
G37*
G36*
X0280512Y0230962D02*
X0279888Y0230838D01*
X0279358Y0230484*
X0279005Y0229955*
X0278881Y0229331*
X0279005Y0228706*
X0279358Y0228177*
X0279888Y0227823*
X0280512Y0227699*
X0281136Y0227823*
X0281665Y0228177*
X0282019Y0228706*
X0282143Y0229331*
X0282019Y0229955*
X0281665Y0230484*
X0281136Y0230838*
X0280512Y0230962*
G37*
G36*
X0272638D02*
X0272013Y0230838D01*
X0271484Y0230484*
X0271131Y0229955*
X0271006Y0229331*
X0271131Y0228706*
X0271484Y0228177*
X0272013Y0227823*
X0272638Y0227699*
X0273262Y0227823*
X0273791Y0228177*
X0274145Y0228706*
X0274269Y0229331*
X0274145Y0229955*
X0273791Y0230484*
X0273262Y0230838*
X0272638Y0230962*
G37*
G36*
X029813Y0230864D02*
X0297506Y0230739D01*
X0296976Y0230386*
X0296623Y0229857*
X0296499Y0229232*
X0296623Y0228608*
X0296976Y0228079*
X0297506Y0227725*
X029813Y0227601*
X0298754Y0227725*
X0299284Y0228079*
X0299637Y0228608*
X0299761Y0229232*
X0299637Y0229857*
X0299284Y0230386*
X0298754Y0230739*
X029813Y0230864*
G37*
G36*
X0286024D02*
X0285399Y0230739D01*
X028487Y0230386*
X0284516Y0229857*
X0284392Y0229232*
X0284516Y0228608*
X028487Y0228079*
X0285399Y0227725*
X0286024Y0227601*
X0286648Y0227725*
X0287177Y0228079*
X0287531Y0228608*
X0287655Y0229232*
X0287531Y0229857*
X0287177Y0230386*
X0286648Y0230739*
X0286024Y0230864*
G37*
G36*
X0266437Y0230765D02*
X0265813Y0230641D01*
X0265283Y0230287*
X026493Y0229758*
X0264806Y0229134*
X026493Y022851*
X0265283Y022798*
X0265813Y0227627*
X0266437Y0227502*
X0267061Y0227627*
X026759Y022798*
X0267944Y022851*
X0268068Y0229134*
X0267944Y0229758*
X026759Y0230287*
X0267061Y0230641*
X0266437Y0230765*
G37*
G36*
X0240613Y02309D02*
X0239989Y0230776D01*
X023946Y0230422*
X0239106Y0229893*
X0238982Y0229269*
X0239106Y0228644*
X023946Y0228115*
X0239989Y0227761*
X0240613Y0227637*
X0241238Y0227761*
X0241556Y0227974*
X0242099Y022798*
X024224Y0227923*
X0242683Y0227627*
X0243307Y0227502*
X0243931Y0227627*
X0244319Y0227886*
X0244521Y0227585*
X024505Y0227231*
X0245674Y0227107*
X0246299Y0227231*
X0246828Y0227585*
X0247049Y0227916*
X0247483Y0227627*
X0248107Y0227502*
X0248731Y0227627*
X0249261Y022798*
X0249614Y022851*
X0249738Y0229134*
X0249614Y0229758*
X0249261Y0230287*
X0248731Y0230641*
X0248107Y0230765*
X0247483Y0230641*
X0246954Y0230287*
X0246732Y0229956*
X0246299Y0230245*
X0245674Y023037*
X024505Y0230245*
X0244662Y0229986*
X0244461Y0230287*
X0243931Y0230641*
X0243307Y0230765*
X0242683Y0230641*
X0242307Y023039*
X0241767Y0230422*
X0241238Y0230776*
X0240613Y02309*
G37*
G36*
X004626Y0228994D02*
X0045636Y0228869D01*
X0045106Y0228516*
X0044753Y0227987*
X0044629Y0227362*
X0044753Y0226738*
X0045106Y0226209*
X0045636Y0225855*
X004626Y0225731*
X0046884Y0225855*
X0047413Y0226209*
X0047767Y0226738*
X0047891Y0227362*
X0047767Y0227987*
X0047413Y0228516*
X0046884Y0228869*
X004626Y0228994*
G37*
G36*
X0293307Y0219151D02*
X0292683Y0219027D01*
X0292154Y0218673*
X0291893Y0218283*
X0291818Y0218261*
X0291412*
X0291337Y0218283*
X0291076Y0218673*
X0290547Y0219027*
X0289923Y0219151*
X0289299Y0219027*
X0288769Y0218673*
X0288416Y0218144*
X0288292Y021752*
X0288416Y0216895*
X0288769Y0216366*
X0289299Y0216013*
X0289923Y0215888*
X0290547Y0216013*
X0291076Y0216366*
X0291337Y0216757*
X0291412Y0216779*
X0291818*
X0291893Y0216757*
X0292154Y0216366*
X0292683Y0216013*
X0293307Y0215888*
X0293931Y0216013*
X0294461Y0216366*
X0294814Y0216895*
X0294938Y021752*
X0294814Y0218144*
X0294461Y0218673*
X0293931Y0219027*
X0293307Y0219151*
G37*
G36*
X0169644Y0211629D02*
X016891Y0211483D01*
X0168287Y0211067*
X0167871Y0210444*
X0167725Y020971*
X0167871Y0208975*
X0168287Y0208352*
X016891Y0207936*
X0169644Y020779*
X0170379Y0207936*
X0171002Y0208352*
X0171418Y0208975*
X0171564Y020971*
X0171418Y0210444*
X0171002Y0211067*
X0170379Y0211483*
X0169644Y0211629*
G37*
G36*
X0357136Y0211625D02*
X0356401Y0211479D01*
X0355778Y0211063*
X0355362Y021044*
X0355216Y0209705*
X0355362Y0208971*
X0355778Y0208348*
X0356401Y0207932*
X0357136Y0207786*
X035787Y0207932*
X0358493Y0208348*
X0358909Y0208971*
X0359055Y0209705*
X0358909Y021044*
X0358493Y0211063*
X035787Y0211479*
X0357136Y0211625*
G37*
G36*
X065748Y0210293D02*
X0656856Y0210169D01*
X0656327Y0209815*
X0655973Y0209286*
X0655849Y0208661*
X0655973Y0208037*
X0656327Y0207508*
X0656856Y0207154*
X065748Y020703*
X0658105Y0207154*
X0658634Y0207508*
X0658988Y0208037*
X0659112Y0208661*
X0658988Y0209286*
X0658634Y0209815*
X0658105Y0210169*
X065748Y0210293*
G37*
G36*
X0184144Y0211779D02*
X0183519Y0211655D01*
X018299Y0211301*
X0182637Y0210772*
X0182512Y0210148*
X0182637Y0209523*
X018299Y0208994*
X0183106Y0208917*
X0183275Y0208758*
X0182922Y0208228*
X0182797Y0207604*
X0182922Y020698*
X0183275Y0206451*
X0183805Y0206097*
X0184429Y0205973*
X0185053Y0206097*
X0185582Y0206451*
X0185936Y020698*
X018606Y0207604*
X0185936Y0208228*
X0185582Y0208758*
X0185467Y0208835*
X0185297Y0208994*
X0185651Y0209523*
X0185775Y0210148*
X0185651Y0210772*
X0185297Y0211301*
X0184768Y0211655*
X0184144Y0211779*
G37*
G36*
X0622047Y0208324D02*
X0621423Y02082D01*
X0620894Y0207846*
X062054Y0207317*
X0620416Y0206693*
X062054Y0206069*
X0620894Y0205539*
X0621423Y0205186*
X0622047Y0205062*
X0622672Y0205186*
X0623201Y0205539*
X0623554Y0206069*
X0623679Y0206693*
X0623554Y0207317*
X0623201Y0207846*
X0622672Y02082*
X0622047Y0208324*
G37*
G36*
Y0202419D02*
X0621423Y0202295D01*
X0621063Y0202054*
X0620703Y0202295*
X0620079Y0202419*
X0619454Y0202295*
X0618925Y0201941*
X0618572Y0201412*
X0618447Y0200787*
X0618572Y0200163*
X0618812Y0199803*
X0618572Y0199443*
X0618447Y0198819*
X0618572Y0198195*
X0618812Y0197835*
X0618572Y0197475*
X0618447Y019685*
X0618572Y0196226*
X0618925Y0195697*
X0619454Y0195343*
X0620079Y0195219*
X0620703Y0195343*
X0621063Y0195584*
X0621423Y0195343*
X0622047Y0195219*
X0622672Y0195343*
X0623201Y0195697*
X0623554Y0196226*
X0623679Y019685*
X0623554Y0197475*
X0623314Y0197835*
X0623554Y0198195*
X0623679Y0198819*
X0623554Y0199443*
X0623314Y0199803*
X0623554Y0200163*
X0623679Y0200787*
X0623554Y0201412*
X0623201Y0201941*
X0622672Y0202295*
X0622047Y0202419*
G37*
G36*
X0373031Y0210293D02*
X0372407Y0210169D01*
X0371878Y0209815*
X0371524Y0209286*
X03714Y0208661*
X0371524Y0208037*
X0371765Y0207677*
X0371524Y0207317*
X03714Y0206693*
X0371524Y0206069*
X0371765Y0205709*
X0371524Y0205349*
X03714Y0204724*
X0371524Y02041*
X0371765Y020374*
X0371524Y020338*
X03714Y0202756*
X0371524Y0202132*
X0371878Y0201602*
X0372407Y0201249*
X0373031Y0201125*
X0373656Y0201249*
X0374185Y0201602*
X0374539Y0202132*
X0374663Y0202756*
X0374539Y020338*
X0374298Y020374*
X0374539Y02041*
X0374663Y0204724*
X0374539Y0205349*
X0374298Y0205709*
X0374539Y0206069*
X0374663Y0206693*
X0374539Y0207317*
X0374298Y0207677*
X0374539Y0208037*
X0374663Y0208661*
X0374539Y0209286*
X0374185Y0209815*
X0373656Y0210169*
X0373031Y0210293*
G37*
G36*
X0338583D02*
X0337958Y0210169D01*
X0337429Y0209815*
X0337075Y0209286*
X0336951Y0208661*
X0337075Y0208037*
X0337316Y0207677*
X0337075Y0207317*
X0336951Y0206693*
X0337075Y0206069*
X0337316Y0205709*
X0337075Y0205349*
X0336951Y0204724*
X0337075Y02041*
X0337316Y020374*
X0337075Y020338*
X0336951Y0202756*
X0337075Y0202132*
X0337429Y0201602*
X0337958Y0201249*
X0338583Y0201125*
X0339207Y0201249*
X0339736Y0201602*
X034009Y0202132*
X0340214Y0202756*
X034009Y020338*
X0339849Y020374*
X034009Y02041*
X0340214Y0204724*
X034009Y0205349*
X0339849Y0205709*
X034009Y0206069*
X0340214Y0206693*
X034009Y0207317*
X0339849Y0207677*
X034009Y0208037*
X0340214Y0208661*
X034009Y0209286*
X0339736Y0209815*
X0339207Y0210169*
X0338583Y0210293*
G37*
G36*
X0119685Y0198383D02*
X0119061Y0198259D01*
X0118532Y0197906*
X0118178Y0197376*
X0118054Y0196752*
X0118178Y0196128*
X0118532Y0195598*
X0119061Y0195245*
X0119685Y0195121*
X0120309Y0195245*
X0120839Y0195598*
X0121192Y0196128*
X0121316Y0196752*
X0121192Y0197376*
X0120839Y0197906*
X0120309Y0198259*
X0119685Y0198383*
G37*
G36*
X0019984Y0202037D02*
X001873Y0201914D01*
X0017523Y0201548*
X0016411Y0200954*
X0015437Y0200154*
X0014637Y0199179*
X0014043Y0198067*
X0013677Y0196861*
X0013553Y0195606*
X0013677Y0194352*
X0014043Y0193145*
X0014637Y0192033*
X0015437Y0191059*
X0016411Y0190259*
X0017523Y0189665*
X001873Y0189299*
X0019984Y0189175*
X0021239Y0189299*
X0022445Y0189665*
X0023557Y0190259*
X0024532Y0191059*
X0025331Y0192033*
X0025926Y0193145*
X0026292Y0194352*
X0026415Y0195606*
X0026292Y0196861*
X0025926Y0198067*
X0025331Y0199179*
X0024532Y0200154*
X0023557Y0200954*
X0022445Y0201548*
X0021239Y0201914*
X0019984Y0202037*
G37*
G36*
X0373031Y0190608D02*
X0372407Y0190483D01*
X0371878Y019013*
X0371524Y0189601*
X03714Y0188976*
X0371524Y0188352*
X0371878Y0187823*
X0372407Y0187469*
X0373031Y0187345*
X0373656Y0187469*
X0374185Y0187823*
X0374539Y0188352*
X0374663Y0188976*
X0374539Y0189601*
X0374185Y019013*
X0373656Y0190483*
X0373031Y0190608*
G37*
G36*
X0386371Y0179781D02*
X0385747Y0179657D01*
X0385218Y0179303*
X0384864Y0178774*
X038474Y017815*
X0384864Y0177525*
X0385218Y0176996*
X0385747Y0176642*
X0386371Y0176518*
X0386996Y0176642*
X0387525Y0176996*
X0387878Y0177525*
X0388003Y017815*
X0387878Y0178774*
X0387525Y0179303*
X0386996Y0179657*
X0386371Y0179781*
G37*
G36*
X0373031Y0181749D02*
X0372407Y0181625D01*
X0371878Y0181272*
X0371524Y0180742*
X03714Y0180118*
X0371524Y0179494*
X0371878Y0178965*
X0371987Y0178892*
Y0178392*
X0371878Y0178319*
X0371524Y017779*
X03714Y0177165*
X0371524Y0176541*
X0371878Y0176012*
X0372407Y0175658*
X0373031Y0175534*
X0373656Y0175658*
X0374185Y0176012*
X0374539Y0176541*
X0374663Y0177165*
X0374539Y017779*
X0374185Y0178319*
X0374076Y0178392*
Y0178892*
X0374185Y0178965*
X0374539Y0179494*
X0374663Y0180118*
X0374539Y0180742*
X0374185Y0181272*
X0373656Y0181625*
X0373031Y0181749*
G37*
G36*
X0107283Y0178797D02*
X0106659Y0178673D01*
X010613Y0178319*
X0105776Y017779*
X0105652Y0177165*
X0105776Y0176541*
X010613Y0176012*
X0106659Y0175658*
X0107283Y0175534*
X0107908Y0175658*
X0108437Y0176012*
X0108791Y0176541*
X0108915Y0177165*
X0108791Y017779*
X0108437Y0178319*
X0107908Y0178673*
X0107283Y0178797*
G37*
G36*
X0401575Y0179781D02*
X040095Y0179657D01*
X0400421Y0179303*
X0400068Y0178774*
X0399943Y017815*
X0400068Y0177525*
X0400196Y0177332*
X0400305Y0176814*
X0400153Y0176574*
X0399954Y0176276*
X0399829Y0175652*
X0399954Y0175027*
X0400307Y0174498*
X0400837Y0174144*
X0401461Y017402*
X0402085Y0174144*
X0402614Y0174498*
X0402968Y0175027*
X0403092Y0175652*
X0402968Y0176276*
X0402839Y0176469*
X040273Y0176987*
X0402883Y0177227*
X0403082Y0177525*
X0403206Y017815*
X0403082Y0178774*
X0402728Y0179303*
X0402199Y0179657*
X0401575Y0179781*
G37*
G36*
X0107283Y0170923D02*
X0106659Y0170799D01*
X010613Y0170445*
X0105776Y0169916*
X0105652Y0169291*
X0105776Y0168667*
X010613Y0168138*
X0106659Y0167784*
X0107283Y016766*
X0107908Y0167784*
X0108437Y0168138*
X0108791Y0168667*
X0108915Y0169291*
X0108791Y0169916*
X0108437Y0170445*
X0107908Y0170799*
X0107283Y0170923*
G37*
G36*
X0373031Y0168923D02*
X0372407Y0168798D01*
X0371878Y0168445*
X0371524Y0167916*
X03714Y0167291*
X0371524Y0166667*
X0371878Y0166138*
X0372407Y0165784*
X0373031Y016566*
X0373656Y0165784*
X0374185Y0166138*
X0374539Y0166667*
X0374663Y0167291*
X0374539Y0167916*
X0374185Y0168445*
X0373656Y0168798*
X0373031Y0168923*
G37*
G36*
X0331802Y0168583D02*
X0331178Y0168459D01*
X0330649Y0168105*
X0330295Y0167576*
X0330171Y0166952*
X0330295Y0166327*
X0330649Y0165798*
X0331178Y0165444*
X0331802Y016532*
X0332427Y0165444*
X0332956Y0165798*
X033331Y0166327*
X0333434Y0166952*
X033331Y0167576*
X0332956Y0168105*
X0332427Y0168459*
X0331802Y0168583*
G37*
G36*
X0683858Y0167408D02*
X0682922Y0167221D01*
X0682128Y0166691*
X0681598Y0165897*
X0681411Y0164961*
X0681598Y0164024*
X0682128Y016323*
X0682922Y01627*
X0683858Y0162514*
X0684795Y01627*
X0685589Y016323*
X0686119Y0164024*
X0686305Y0164961*
X0686119Y0165897*
X0685589Y0166691*
X0684795Y0167221*
X0683858Y0167408*
G37*
G36*
X0386372Y0165098D02*
X0385748Y0164973D01*
X0385218Y016462*
X0384865Y0164091*
X038474Y0163466*
X0384865Y0162842*
X0385082Y0162516*
X0385201Y0162232*
X0385106Y0161787*
X0384925Y0161517*
X0384801Y0160893*
X0384925Y0160268*
X0385279Y0159739*
X038544Y0159632*
Y015903*
X0385304Y015894*
X038495Y0158411*
X0384826Y0157787*
X038495Y0157162*
X0385304Y0156633*
X0385833Y0156279*
X0386458Y0156155*
X0387082Y0156279*
X0387611Y0156633*
X0387965Y0157162*
X0388089Y0157787*
X0387965Y0158411*
X0387611Y015894*
X0387451Y0159047*
Y0159649*
X0387586Y0159739*
X038794Y0160268*
X0388064Y0160893*
X038794Y0161517*
X0387722Y0161843*
X0387603Y0162127*
X0387699Y0162572*
X0387879Y0162842*
X0388003Y0163466*
X0387879Y0164091*
X0387525Y016462*
X0386996Y0164973*
X0386372Y0165098*
G37*
G36*
X0401575Y0166986D02*
X040095Y0166861D01*
X0400421Y0166508*
X0400068Y0165979*
X0399943Y0165354*
X0400068Y016473*
X0400421Y0164201*
Y0163987*
X0400068Y0163457*
X0399943Y0162833*
X0400068Y0162209*
X0400421Y0161679*
Y0161587*
X0400068Y0161057*
X0399943Y0160433*
X0400068Y0159809*
X0400421Y015928*
X040053Y0159207*
Y0158707*
X0400421Y0158634*
X0400068Y0158105*
X0399943Y015748*
X0400068Y0156856*
X0400421Y0156327*
X040095Y0155973*
X0401575Y0155849*
X0402199Y0155973*
X0402728Y0156327*
X0403082Y0156856*
X0403206Y015748*
X0403082Y0158105*
X0402728Y0158634*
X0402619Y0158707*
Y0159207*
X0402728Y015928*
X0403082Y0159809*
X0403206Y0160433*
X0403082Y0161057*
X0402728Y0161587*
Y0161679*
X0403082Y0162209*
X0403206Y0162833*
X0403082Y0163457*
X0402728Y0163987*
Y0164201*
X0403082Y016473*
X0403206Y0165354*
X0403082Y0165979*
X0402728Y0166508*
X0402199Y0166861*
X0401575Y0166986*
G37*
G36*
X0188944Y0153238D02*
X018832Y0153114D01*
X0187791Y015276*
X0187437Y0152231*
X0187313Y0151607*
X0187437Y0150982*
X0187791Y0150453*
X018832Y01501*
X0188944Y0149975*
X0189569Y01501*
X0190098Y0150453*
X0190452Y0150982*
X0190576Y0151607*
X0190452Y0152231*
X0190098Y015276*
X0189569Y0153114*
X0188944Y0153238*
G37*
G36*
X0149606Y0153206D02*
X0148982Y0153082D01*
X0148453Y0152728*
X0148099Y0152199*
X0147975Y0151575*
X0148099Y0150951*
X0148453Y0150421*
X0148982Y0150068*
X0149606Y0149943*
X0150231Y0150068*
X015076Y0150421*
X0151113Y0150951*
X0151238Y0151575*
X0151113Y0152199*
X015076Y0152728*
X0150231Y0153082*
X0149606Y0153206*
G37*
G36*
X0134843D02*
X0134218Y0153082D01*
X0133689Y0152728*
X0133335Y0152199*
X0133211Y0151575*
X0133335Y0150951*
X0133689Y0150421*
X0134218Y0150068*
X0134843Y0149943*
X0135467Y0150068*
X0135996Y0150421*
X013635Y0150951*
X0136474Y0151575*
X013635Y0152199*
X0135996Y0152728*
X0135467Y0153082*
X0134843Y0153206*
G37*
G36*
X0597441Y0147301D02*
X0596817Y0147177D01*
X0596457Y0146936*
X0596097Y0147177*
X0595472Y0147301*
X0594848Y0147177*
X0594319Y0146823*
X0593965Y0146294*
X0593841Y0145669*
X0593965Y0145045*
X0594206Y0144685*
X0593965Y0144325*
X0593841Y0143701*
X0593965Y0143077*
X0594206Y0142717*
X0593965Y0142357*
X0593841Y0141732*
X0593965Y0141108*
X0594319Y0140579*
X0594848Y0140225*
X0595472Y0140101*
X0596097Y0140225*
X0596457Y0140466*
X0596817Y0140225*
X0597441Y0140101*
X0598065Y0140225*
X0598595Y0140579*
X0598948Y0141108*
X0599072Y0141732*
X0598948Y0142357*
X0598708Y0142717*
X0598948Y0143077*
X0599072Y0143701*
X0598948Y0144325*
X0598708Y0144685*
X0598948Y0145045*
X0599072Y0145669*
X0598948Y0146294*
X0598595Y0146823*
X0598065Y0147177*
X0597441Y0147301*
G37*
G36*
X011939Y0145135D02*
X0118765Y0145011D01*
X0118236Y0144658*
X0117883Y0144128*
X0117758Y0143504*
X0117883Y014288*
X0118236Y014235*
X0118765Y0141997*
X011939Y0141873*
X0120014Y0141997*
X0120543Y014235*
X0120897Y014288*
X0121021Y0143504*
X0120897Y0144128*
X0120543Y0144658*
X0120014Y0145011*
X011939Y0145135*
G37*
G36*
X0019984Y0149537D02*
X001873Y0149414D01*
X0017523Y0149048*
X0016411Y0148453*
X0015437Y0147654*
X0014637Y0146679*
X0014043Y0145567*
X0013677Y0144361*
X0013553Y0143106*
X0013677Y0141852*
X0014043Y0140645*
X0014637Y0139533*
X0015437Y0138559*
X0016411Y0137759*
X0017523Y0137165*
X001873Y0136799*
X0019984Y0136675*
X0021239Y0136799*
X0022445Y0137165*
X0023557Y0137759*
X0024532Y0138559*
X0025331Y0139533*
X0025926Y0140645*
X0026292Y0141852*
X0026415Y0143106*
X0026292Y0144361*
X0025926Y0145567*
X0025331Y0146679*
X0024532Y0147654*
X0023557Y0148453*
X0022445Y0149048*
X0021239Y0149414*
X0019984Y0149537*
G37*
G36*
X0341142Y0144053D02*
X0340517Y0143928D01*
X0339988Y0143575*
X0339635Y0143046*
X033951Y0142421*
X0339635Y0141797*
X0339988Y0141268*
X0340169Y0141147*
Y0140546*
X0339988Y0140425*
X0339635Y0139896*
X033951Y0139272*
X0339635Y0138647*
X0339988Y0138118*
X0340095Y0138047*
X034013Y0137468*
X0339776Y0136939*
X0339652Y0136314*
X0339776Y013569*
X034013Y0135161*
X0340244Y0135084*
Y0135071*
X033989Y0134541*
X0339766Y0133917*
X033989Y0133293*
X0340244Y0132764*
X0340773Y013241*
X0341397Y0132286*
X0342022Y013241*
X0342551Y0132764*
X0342905Y0133293*
X0343029Y0133917*
X0342905Y0134541*
X0342551Y0135071*
X0342437Y0135147*
Y0135161*
X034279Y013569*
X0342915Y0136314*
X034279Y0136939*
X0342437Y0137468*
X0342329Y013754*
X0342295Y0138118*
X0342649Y0138647*
X0342773Y0139272*
X0342649Y0139896*
X0342295Y0140425*
X0342115Y0140546*
Y0141147*
X0342295Y0141268*
X0342649Y0141797*
X0342773Y0142421*
X0342649Y0143046*
X0342295Y0143575*
X0341766Y0143928*
X0341142Y0144053*
G37*
G36*
X0169644Y0132889D02*
X016891Y0132743D01*
X0168287Y0132327*
X0167871Y0131704*
X0167725Y013097*
X0167871Y0130235*
X0168287Y0129612*
X016891Y0129196*
X0169644Y012905*
X0170379Y0129196*
X0171002Y0129612*
X0171418Y0130235*
X0171564Y013097*
X0171418Y0131704*
X0171002Y0132327*
X0170379Y0132743*
X0169644Y0132889*
G37*
G36*
X0357136Y0132885D02*
X0356401Y0132739D01*
X0355778Y0132323*
X0355362Y01317*
X0355216Y0130965*
X0355362Y0130231*
X0355778Y0129608*
X0356401Y0129192*
X0357136Y0129046*
X035787Y0129192*
X0358493Y0129608*
X0358909Y0130231*
X0359055Y0130965*
X0358909Y01317*
X0358493Y0132323*
X035787Y0132739*
X0357136Y0132885*
G37*
G36*
X0045276Y0122694D02*
X0044651Y012257D01*
X0044122Y0122216*
X0043768Y0121687*
X0043644Y0121063*
X0043768Y0120439*
X0044122Y0119909*
X0044651Y0119556*
X0045276Y0119432*
X00459Y0119556*
X0046429Y0119909*
X0046783Y0120439*
X0046907Y0121063*
X0046783Y0121687*
X0046429Y0122216*
X00459Y012257*
X0045276Y0122694*
G37*
G36*
X0112205Y0118757D02*
X011158Y0118633D01*
X0111051Y011828*
X0110698Y011775*
X0110573Y0117126*
X0110698Y0116502*
X0111051Y0115972*
X011158Y0115619*
X0112205Y0115495*
X0112829Y0115619*
X0113358Y0115972*
X0113712Y0116502*
X0113836Y0117126*
X0113712Y011775*
X0113358Y011828*
X0112829Y0118633*
X0112205Y0118757*
G37*
G36*
X0282677Y0099269D02*
X0282053Y0099145D01*
X0281524Y0098791*
X0281075*
X0280546Y0099145*
X0279921Y0099269*
X0279297Y0099145*
X0278768Y0098791*
X0278647Y0098611*
X0278046*
X0277925Y0098791*
X0277396Y0099145*
X0276772Y0099269*
X0276147Y0099145*
X0275618Y0098791*
X0275169*
X027464Y0099145*
X0274016Y0099269*
X0273392Y0099145*
X0272862Y0098791*
X0272742Y0098611*
X027214*
X027202Y0098791*
X027149Y0099145*
X0270866Y0099269*
X0270242Y0099145*
X0269713Y0098791*
X0269264*
X0268735Y0099145*
X026811Y0099269*
X0267486Y0099145*
X0266957Y0098791*
X0266836Y0098611*
X0266235*
X0266114Y0098791*
X0265585Y0099145*
X0264961Y0099269*
X0264336Y0099145*
X0263807Y0098791*
X0263358*
X0262829Y0099145*
X0262205Y0099269*
X026158Y0099145*
X0261051Y0098791*
X0260698Y0098262*
X0260573Y0097638*
X0260698Y0097013*
X0261051Y0096484*
X026158Y0096131*
X0262205Y0096006*
X0262829Y0096131*
X0263358Y0096484*
X0263807*
X0264336Y0096131*
X0264961Y0096006*
X0265585Y0096131*
X0266114Y0096484*
X0266235Y0096665*
X0266836*
X0266957Y0096484*
X0267486Y0096131*
X026811Y0096006*
X0268735Y0096131*
X0269264Y0096484*
X0269713*
X0270242Y0096131*
X0270866Y0096006*
X027149Y0096131*
X027202Y0096484*
X027214Y0096665*
X0272742*
X0272862Y0096484*
X0273392Y0096131*
X0274016Y0096006*
X027464Y0096131*
X0275169Y0096484*
X0275618*
X0276147Y0096131*
X0276772Y0096006*
X0277396Y0096131*
X0277925Y0096484*
X0278046Y0096665*
X0278647*
X0278768Y0096484*
X0279297Y0096131*
X0279921Y0096006*
X0280546Y0096131*
X0281075Y0096484*
X0281524*
X0282053Y0096131*
X0282677Y0096006*
X0283301Y0096131*
X0283831Y0096484*
X0284184Y0097013*
X0284309Y0097638*
X0284184Y0098262*
X0283831Y0098791*
X0283301Y0099145*
X0282677Y0099269*
G37*
G36*
X0299015Y0097765D02*
X0298281Y0097619D01*
X0297658Y0097203*
X0297242Y009658*
X0297096Y0095846*
X0297242Y0095111*
X0297658Y0094488*
X0298281Y0094072*
X0299015Y0093926*
X029975Y0094072*
X0300373Y0094488*
X0300789Y0095111*
X0300935Y0095846*
X0300789Y009658*
X0300373Y0097203*
X029975Y0097619*
X0299015Y0097765*
G37*
G36*
X0220275D02*
X0219541Y0097619D01*
X0218918Y0097203*
X0218502Y009658*
X0218356Y0095846*
X0218502Y0095111*
X0218918Y0094488*
X0219541Y0094072*
X0220275Y0093926*
X022101Y0094072*
X0221633Y0094488*
X0222049Y0095111*
X0222195Y0095846*
X0222049Y009658*
X0221633Y0097203*
X022101Y0097619*
X0220275Y0097765*
G37*
G36*
X0119587Y0093068D02*
X0118962Y0092944D01*
X0118433Y009259*
X0118079Y0092061*
X0117955Y0091437*
X0118079Y0090813*
X0118433Y0090284*
X0118962Y008993*
X0119587Y0089806*
X0120211Y008993*
X012074Y0090284*
X0121094Y0090813*
X0121218Y0091437*
X0121094Y0092061*
X012074Y009259*
X0120211Y0092944*
X0119587Y0093068*
G37*
G36*
X0361755Y0098353D02*
X0360441Y0098224D01*
X0359177Y0097841*
X0358012Y0097218*
X0356991Y009638*
X0356153Y0095359*
X035553Y0094194*
X0355147Y009293*
X0355017Y0091615*
X0355147Y0090301*
X035553Y0089037*
X0356153Y0087872*
X0356991Y0086851*
X0358012Y0086013*
X0359177Y0085391*
X0360441Y0085007*
X0361755Y0084878*
X036307Y0085007*
X0364334Y0085391*
X0365499Y0086013*
X036652Y0086851*
X0367358Y0087872*
X0367981Y0089037*
X0368364Y0090301*
X0368493Y0091615*
X0368364Y009293*
X0367981Y0094194*
X0367358Y0095359*
X036652Y009638*
X0365499Y0097218*
X0364334Y0097841*
X036307Y0098224*
X0361755Y0098353*
G37*
G36*
X0165255D02*
X0163941Y0098224D01*
X0162677Y0097841*
X0161512Y0097218*
X0160491Y009638*
X0159653Y0095359*
X015903Y0094194*
X0158647Y009293*
X0158518Y0091615*
X0158647Y0090301*
X015903Y0089037*
X0159653Y0087872*
X0160491Y0086851*
X0161512Y0086013*
X0162677Y0085391*
X0163941Y0085007*
X0165255Y0084878*
X016657Y0085007*
X0167834Y0085391*
X0168999Y0086013*
X017002Y0086851*
X0170858Y0087872*
X0171481Y0089037*
X0171864Y0090301*
X0171993Y0091615*
X0171864Y009293*
X0171481Y0094194*
X0170858Y0095359*
X017002Y009638*
X0168999Y0097218*
X0167834Y0097841*
X016657Y0098224*
X0165255Y0098353*
G37*
G36*
X0019984Y0097037D02*
X001873Y0096914D01*
X0017523Y0096548*
X0016411Y0095954*
X0015437Y0095154*
X0014637Y0094179*
X0014043Y0093067*
X0013677Y0091861*
X0013553Y0090606*
X0013677Y0089352*
X0014043Y0088145*
X0014637Y0087033*
X0015437Y0086059*
X0016411Y0085259*
X0017523Y0084665*
X001873Y0084299*
X0019984Y0084175*
X0021239Y0084299*
X0022445Y0084665*
X0023557Y0085259*
X0024532Y0086059*
X0025331Y0087033*
X0025926Y0088145*
X0026292Y0089352*
X0026415Y0090606*
X0026292Y0091861*
X0025926Y0093067*
X0025331Y0094179*
X0024532Y0095154*
X0023557Y0095954*
X0022445Y0096548*
X0021239Y0096914*
X0019984Y0097037*
G37*
G36*
X055873Y0092581D02*
X0557543Y0092425D01*
X0556436Y0091966*
X0555485Y0091237*
X0554756Y0090287*
X0554297Y008918*
X0554141Y0087992*
X0554297Y0086804*
X0554756Y0085698*
X0555485Y0084747*
X0556436Y0084018*
X0557543Y0083559*
X055873Y0083403*
X0559918Y0083559*
X0561025Y0084018*
X0561975Y0084747*
X0562705Y0085698*
X0563163Y0086804*
X0563319Y0087992*
X0563163Y008918*
X0562705Y0090287*
X0561975Y0091237*
X0561025Y0091966*
X0559918Y0092425*
X055873Y0092581*
G37*
G36*
X0398888D02*
X03977Y0092425D01*
X0396593Y0091966*
X0395643Y0091237*
X0394913Y0090287*
X0394455Y008918*
X0394299Y0087992*
X0394455Y0086804*
X0394913Y0085698*
X0395643Y0084747*
X0396593Y0084018*
X03977Y0083559*
X0398888Y0083403*
X0400075Y0083559*
X0401182Y0084018*
X0402133Y0084747*
X0402862Y0085698*
X0403321Y0086804*
X0403477Y0087992*
X0403321Y008918*
X0402862Y0090287*
X0402133Y0091237*
X0401182Y0091966*
X0400075Y0092425*
X0398888Y0092581*
G37*
G36*
X0275984Y0081159D02*
X027536Y0081035D01*
X0274831Y0080681*
X0274382*
X0273853Y0081035*
X0273228Y0081159*
X0272604Y0081035*
X0272075Y0080681*
X0271721Y0080152*
X0271597Y0079528*
X0271721Y0078903*
X0272075Y0078374*
X0272604Y007802*
X0273228Y0077896*
X0273853Y007802*
X0274382Y0078374*
X0274831*
X027536Y007802*
X0275984Y0077896*
X0276608Y007802*
X0277138Y0078374*
X0277491Y0078903*
X0277616Y0079528*
X0277491Y0080152*
X0277138Y0080681*
X0276608Y0081035*
X0275984Y0081159*
G37*
G36*
X0269291D02*
X0268667Y0081035D01*
X0268138Y0080681*
X0267689*
X026716Y0081035*
X0266535Y0081159*
X0265911Y0081035*
X0265382Y0080681*
X0265028Y0080152*
X0264904Y0079528*
X0265028Y0078903*
X0265382Y0078374*
X0265911Y007802*
X0266535Y0077896*
X026716Y007802*
X0267689Y0078374*
X0268138*
X0268667Y007802*
X0269291Y0077896*
X0269916Y007802*
X0270445Y0078374*
X0270798Y0078903*
X0270923Y0079528*
X0270798Y0080152*
X0270445Y0080681*
X0269916Y0081035*
X0269291Y0081159*
G37*
G36*
X0262598D02*
X0261974Y0081035D01*
X0261445Y0080681*
X0260996*
X0260467Y0081035*
X0259842Y0081159*
X0259218Y0081035*
X0258689Y0080681*
X0258335Y0080152*
X0258211Y0079528*
X0258335Y0078903*
X0258689Y0078374*
X0259218Y007802*
X0259842Y0077896*
X0260467Y007802*
X0260996Y0078374*
X0261445*
X0261974Y007802*
X0262598Y0077896*
X0263223Y007802*
X0263752Y0078374*
X0264106Y0078903*
X026423Y0079528*
X0264106Y0080152*
X0263752Y0080681*
X0263223Y0081035*
X0262598Y0081159*
G37*
G36*
X028937D02*
X0288746Y0081035D01*
X0288216Y0080681*
X0288096Y0080501*
X0287495*
X0287374Y0080681*
X0286845Y0081035*
X0286221Y0081159*
X0285596Y0081035*
X0285067Y0080681*
X0284713Y0080152*
X0284704Y0080104*
X0284194*
X0284184Y0080152*
X0283831Y0080681*
X0283301Y0081035*
X0282677Y0081159*
X0282053Y0081035*
X0281524Y0080681*
X0281075*
X0280546Y0081035*
X0279921Y0081159*
X0279297Y0081035*
X0278768Y0080681*
X0278414Y0080152*
X027829Y0079528*
X0278414Y0078903*
X0278768Y0078374*
X0279297Y007802*
X0279921Y0077896*
X0280546Y007802*
X0281075Y0078374*
X0281524*
X0282053Y007802*
X0282677Y0077896*
X0283301Y007802*
X0283831Y0078374*
X0284184Y0078903*
X0284194Y0078951*
X0284704*
X0284713Y0078903*
X0285067Y0078374*
X0285596Y007802*
X0286221Y0077896*
X0286845Y007802*
X0287374Y0078374*
X0287495Y0078554*
X0288096*
X0288216Y0078374*
X0288746Y007802*
X028937Y0077896*
X0289994Y007802*
X0290524Y0078374*
X0290877Y0078903*
X0291001Y0079528*
X0290877Y0080152*
X0290524Y0080681*
X0289994Y0081035*
X028937Y0081159*
G37*
G36*
X0370669Y0076262D02*
X0369808Y0076148D01*
X0369005Y0075816*
X0368316Y0075287*
X0367787Y0074597*
X0367454Y0073795*
X0367341Y0072933*
X0367454Y0072072*
X0367787Y0071269*
X0368316Y0070579*
X0369005Y0070051*
X0369808Y0069718*
X0370669Y0069605*
X0371531Y0069718*
X0372334Y0070051*
X0373023Y0070579*
X0373552Y0071269*
X0373884Y0072072*
X0373998Y0072933*
X0373884Y0073795*
X0373552Y0074597*
X0373023Y0075287*
X0372334Y0075816*
X0371531Y0076148*
X0370669Y0076262*
G37*
G36*
X0213583Y0057734D02*
X0212958Y0057609D01*
X0212598Y0057369*
X0212239Y0057609*
X0211614Y0057734*
X021099Y0057609*
X021063Y0057369*
X021027Y0057609*
X0209646Y0057734*
X0209021Y0057609*
X0208492Y0057256*
X0208138Y0056727*
X0208014Y0056102*
X0208138Y0055478*
X0208379Y0055118*
X0208138Y0054758*
X0208014Y0054134*
X0208138Y005351*
X0208492Y005298*
X0209021Y0052627*
X0209646Y0052503*
X021027Y0052627*
X021063Y0052867*
X021099Y0052627*
X0211614Y0052503*
X0212239Y0052627*
X0212598Y0052867*
X0212958Y0052627*
X0213583Y0052503*
X0214207Y0052627*
X0214736Y005298*
X021509Y005351*
X0215214Y0054134*
X021509Y0054758*
X0214849Y0055118*
X021509Y0055478*
X0215214Y0056102*
X021509Y0056727*
X0214736Y0057256*
X0214207Y0057609*
X0213583Y0057734*
G37*
G36*
X0246988Y004273D02*
X0246364Y0042606D01*
X0245835Y0042252*
X0245481Y0041723*
X0245357Y0041099*
X0245481Y0040475*
X0245835Y0039945*
X0246364Y0039592*
X0246988Y0039467*
X0247613Y0039592*
X0248142Y0039945*
X0248495Y0040475*
X024862Y0041099*
X0248495Y0041723*
X0248142Y0042252*
X0247613Y0042606*
X0246988Y004273*
G37*
G36*
X0298046Y0042547D02*
X0297421Y0042423D01*
X0296892Y0042069*
X0296538Y004154*
X0296414Y0040915*
X0296538Y0040291*
X0296892Y0039762*
X0297421Y0039408*
X0298046Y0039284*
X029867Y0039408*
X0299199Y0039762*
X0299553Y0040291*
X0299677Y0040915*
X0299553Y004154*
X0299199Y0042069*
X029867Y0042423*
X0298046Y0042547*
G37*
G36*
X0301969Y0042182D02*
X0301344Y0042058D01*
X0300815Y0041705*
X0300461Y0041175*
X0300337Y0040551*
X0300461Y0039927*
X0300815Y0039398*
X0301344Y0039044*
X0301969Y003892*
X0302593Y0039044*
X0303122Y0039398*
X0303476Y0039927*
X03036Y0040551*
X0303476Y0041175*
X0303122Y0041705*
X0302593Y0042058*
X0301969Y0042182*
G37*
G36*
X0282198Y0042417D02*
X0281574Y0042292D01*
X0281045Y0041939*
X0280691Y004141*
X0280567Y0040785*
X0280691Y0040161*
X0281045Y0039632*
X0281574Y0039278*
X0282198Y0039154*
X0282823Y0039278*
X0283352Y0039632*
X028346Y0039793*
X0283528Y0039813*
X0284038Y0039759*
X0284279Y0039398*
X0284809Y0039044*
X0285433Y003892*
X0286057Y0039044*
X0286587Y0039398*
X028694Y0039927*
X0287064Y0040551*
X028694Y0041175*
X0286587Y0041705*
X0286057Y0042058*
X0285433Y0042182*
X0284809Y0042058*
X0284279Y0041705*
X0284172Y0041543*
X0284103Y0041524*
X0283593Y0041578*
X0283352Y0041939*
X0282823Y0042292*
X0282198Y0042417*
G37*
G36*
X0270472Y0042182D02*
X0269848Y0042058D01*
X0269319Y0041705*
X0268965Y0041175*
X0268841Y0040551*
X0268965Y0039927*
X0269319Y0039398*
X0269848Y0039044*
X0270472Y003892*
X0271097Y0039044*
X0271626Y0039398*
X027198Y0039927*
X0272104Y0040551*
X027198Y0041175*
X0271626Y0041705*
X0271097Y0042058*
X0270472Y0042182*
G37*
G36*
X0266535D02*
X0265911Y0042058D01*
X0265382Y0041705*
X0265028Y0041175*
X0264904Y0040551*
X0265028Y0039927*
X0265382Y0039398*
X0265911Y0039044*
X0266535Y003892*
X026716Y0039044*
X0267689Y0039398*
X0268043Y0039927*
X0268167Y0040551*
X0268043Y0041175*
X0267689Y0041705*
X026716Y0042058*
X0266535Y0042182*
G37*
G36*
X0251181D02*
X0250557Y0042058D01*
X0250028Y0041705*
X0249674Y0041175*
X024955Y0040551*
X0249674Y0039927*
X0250028Y0039398*
X0250557Y0039044*
X0251181Y003892*
X0251805Y0039044*
X0252335Y0039398*
X0252688Y0039927*
X0252812Y0040551*
X0252688Y0041175*
X0252335Y0041705*
X0251805Y0042058*
X0251181Y0042182*
G37*
G36*
X0238976D02*
X0238352Y0042058D01*
X0237823Y0041705*
X0237469Y0041175*
X0237345Y0040551*
X0237469Y0039927*
X0237823Y0039398*
X0238352Y0039044*
X0238976Y003892*
X0239601Y0039044*
X024013Y0039398*
X0240484Y0039927*
X0240608Y0040551*
X0240484Y0041175*
X024013Y0041705*
X0239601Y0042058*
X0238976Y0042182*
G37*
G36*
X0235039D02*
X0234415Y0042058D01*
X0233886Y0041705*
X0233532Y0041175*
X0233408Y0040551*
X0233532Y0039927*
X0233886Y0039398*
X0234415Y0039044*
X0235039Y003892*
X0235664Y0039044*
X0236193Y0039398*
X0236546Y0039927*
X0236671Y0040551*
X0236546Y0041175*
X0236193Y0041705*
X0235664Y0042058*
X0235039Y0042182*
G37*
G36*
X0207087Y0039427D02*
X0206462Y0039302D01*
X0205933Y0038949*
X0205579Y003842*
X0205455Y0037795*
X0205579Y0037171*
X0205933Y0036642*
X0206462Y0036288*
X0207087Y0036164*
X0207711Y0036288*
X020824Y0036642*
X0208594Y0037171*
X0208718Y0037795*
X0208594Y003842*
X020824Y0038949*
X0207711Y0039302*
X0207087Y0039427*
G37*
G36*
X0187205Y0030371D02*
X018658Y0030247D01*
X0186221Y0030007*
X0185861Y0030247*
X0185236Y0030371*
X0184612Y0030247*
X0184252Y0030007*
X0183892Y0030247*
X0183268Y0030371*
X0182643Y0030247*
X0182114Y0029894*
X0181761Y0029364*
X0181636Y002874*
X0181761Y0028116*
X0182114Y0027587*
X0182295Y0027466*
Y0026865*
X0182114Y0026744*
X0181761Y0026215*
X0181636Y0025591*
X0181761Y0024966*
X0182114Y0024437*
X0182643Y0024083*
X0183268Y0023959*
X0183892Y0024083*
X0184252Y0024324*
X0184612Y0024083*
X0185236Y0023959*
X0185861Y0024083*
X0186221Y0024324*
X018658Y0024083*
X0187205Y0023959*
X0187829Y0024083*
X0188358Y0024437*
X0188712Y0024966*
X0188836Y0025591*
X0188712Y0026215*
X0188358Y0026744*
X0188178Y0026865*
Y0027466*
X0188358Y0027587*
X0188712Y0028116*
X0188836Y002874*
X0188712Y0029364*
X0188358Y0029894*
X0187829Y0030247*
X0187205Y0030371*
G37*
G36*
X0211221D02*
X0210596Y0030247D01*
X0210067Y0029894*
X0209713Y0029364*
X0209704Y0029316*
X0209194*
X0209184Y0029364*
X0208831Y0029894*
X0208301Y0030247*
X0207677Y0030371*
X0207053Y0030247*
X0206524Y0029894*
X020617Y0029364*
X0206046Y002874*
X020617Y0028116*
X0206524Y0027587*
X0206704Y0027466*
Y0026865*
X0206524Y0026744*
X020617Y0026215*
X0206046Y0025591*
X020617Y0024966*
X0206524Y0024437*
X0207053Y0024083*
X0207677Y0023959*
X0208301Y0024083*
X0208831Y0024437*
X0209184Y0024966*
X0209194Y0025014*
X0209704*
X0209713Y0024966*
X0210067Y0024437*
X0210596Y0024083*
X0211221Y0023959*
X0211845Y0024083*
X0212374Y0024437*
X0212728Y0024966*
X0212852Y0025591*
X0212728Y0026215*
X0212374Y0026744*
X0212193Y0026865*
Y0027466*
X0212374Y0027587*
X0212728Y0028116*
X0212852Y002874*
X0212728Y0029364*
X0212374Y0029894*
X0211845Y0030247*
X0211221Y0030371*
G37*
G36*
X0261024Y0029584D02*
X0260399Y002946D01*
X025987Y0029106*
X025975Y0028926*
X0259148*
X0259028Y0029106*
X0258498Y002946*
X0257874Y0029584*
X025725Y002946*
X025672Y0029106*
X0256367Y0028577*
X0256243Y0027953*
X0256367Y0027329*
X025672Y0026799*
X025725Y0026446*
X0257874Y0026321*
X0258498Y0026446*
X0259028Y0026799*
X0259148Y002698*
X025975*
X025987Y0026799*
X0260399Y0026446*
X0261024Y0026321*
X0261648Y0026446*
X0262177Y0026799*
X0262531Y0027329*
X0262655Y0027953*
X0262531Y0028577*
X0262177Y0029106*
X0261648Y002946*
X0261024Y0029584*
G37*
G36*
X0244488D02*
X0243864Y002946D01*
X0243335Y0029106*
X0243214Y0028926*
X0242613*
X0242492Y0029106*
X0241963Y002946*
X0241339Y0029584*
X0240714Y002946*
X0240185Y0029106*
X0239831Y0028577*
X0239707Y0027953*
X0239831Y0027329*
X0240185Y0026799*
X0240714Y0026446*
X0241339Y0026321*
X0241963Y0026446*
X0242492Y0026799*
X0242613Y002698*
X0243214*
X0243335Y0026799*
X0243864Y0026446*
X0244488Y0026321*
X0245112Y0026446*
X0245642Y0026799*
X0245995Y0027329*
X0246119Y0027953*
X0245995Y0028577*
X0245642Y0029106*
X0245112Y002946*
X0244488Y0029584*
G37*
G36*
X0293701D02*
X0293076Y002946D01*
X0292547Y0029106*
X0292425Y0028924*
X0291824*
X0291703Y0029105*
X0291174Y0029458*
X0290549Y0029582*
X0289925Y0029458*
X0289396Y0029105*
X0289042Y0028575*
X0288918Y0027951*
X0289042Y0027327*
X0289396Y0026798*
X0289925Y0026444*
X0290549Y002632*
X0291174Y0026444*
X0291703Y0026798*
X0291825Y002698*
X0292426*
X0292547Y0026799*
X0293076Y0026446*
X0293701Y0026321*
X0294325Y0026446*
X0294854Y0026799*
X0295208Y0027329*
X0295332Y0027953*
X0295208Y0028577*
X0294854Y0029106*
X0294325Y002946*
X0293701Y0029584*
G37*
G36*
X0274882Y0029862D02*
X0274258Y0029738D01*
X0273728Y0029385*
X0273375Y0028855*
X0273251Y0028231*
X0273375Y0027607*
X0273728Y0027078*
X0274258Y0026724*
X0274882Y00266*
X0275506Y0026724*
X0276035Y0027078*
X0276625Y002706*
X0276799Y0026799*
X0277328Y0026446*
X0277953Y0026321*
X0278577Y0026446*
X0279106Y0026799*
X027946Y0027329*
X0279584Y0027953*
X027946Y0028577*
X0279106Y0029106*
X0278577Y002946*
X0277953Y0029584*
X0277328Y002946*
X0276799Y0029106*
X027621Y0029124*
X0276035Y0029385*
X0275506Y0029738*
X0274882Y0029862*
G37*
G36*
X0215158Y0030371D02*
X0214533Y0030247D01*
X0214004Y0029894*
X021365Y0029364*
X0213526Y002874*
X021365Y0028116*
X0214004Y0027587*
X0214184Y0027466*
Y0026865*
X0214004Y0026744*
X021365Y0026215*
X0213526Y0025591*
X021365Y0024966*
X0214004Y0024437*
X0214533Y0024083*
X0215158Y0023959*
X0215782Y0024083*
X0216311Y0024437*
X0216665Y0024966*
X0216789Y0025591*
X0216665Y0026215*
X0216311Y0026744*
X021613Y0026865*
Y0027466*
X0216311Y0027587*
X0216665Y0028116*
X0216789Y002874*
X0216665Y0029364*
X0216311Y0029894*
X0215782Y0030247*
X0215158Y0030371*
G37*
G36*
X0028543Y0050152D02*
X0026456Y0049988D01*
X0024421Y0049499*
X0022487Y0048698*
X0020702Y0047604*
X001911Y0046245*
X001775Y0044653*
X0016656Y0042868*
X0015855Y0040934*
X0015366Y0038898*
X0015202Y0036811*
X0015366Y0034724*
X0015855Y0032688*
X0016656Y0030754*
X001775Y0028969*
X001911Y0027377*
X0020702Y0026018*
X0022487Y0024924*
X0024421Y0024123*
X0026456Y0023634*
X0028543Y002347*
X003063Y0023634*
X0032666Y0024123*
X00346Y0024924*
X0036385Y0026018*
X0037977Y0027377*
X0039336Y0028969*
X004043Y0030754*
X0041232Y0032688*
X004172Y0034724*
X0041884Y0036811*
X004172Y0038898*
X0041232Y0040934*
X004043Y0042868*
X0039336Y0044653*
X0037977Y0046245*
X0036385Y0047604*
X00346Y0048698*
X0032666Y0049499*
X003063Y0049988*
X0028543Y0050152*
G37*
%LNtimecard-dc-beta-v1-3*%
%LPD*%
G54D108*
X0009984Y0258106D03*
Y0238106D03*
X0029984D03*
Y0258106D03*
X0009984Y0100606D03*
Y0080606D03*
X0029984D03*
Y0100606D03*
X0009984Y0153106D03*
Y0133106D03*
X0029984D03*
Y0153106D03*
X0009984Y0205606D03*
Y0185606D03*
X0029984D03*
Y0205606D03*
G54D120*
X0398888Y0247835D03*
X055873Y0167913D03*
G54D121*
X0513622Y0426181D03*
G54D126*
X0045276Y0112205D03*
X004626Y0218504D03*
X0052689Y0207306D03*
X0101378Y0161417D03*
X0270669Y0309087D03*
X0261811Y0309055D03*
X0356299Y0303118D03*
X0366142D03*
X025889Y0242126D03*
X0525591Y0271654D03*
X0512795Y0279528D03*
Y028248D03*
X0519685Y0298228D03*
X0490158Y0270638D03*
X0505905Y0283465D03*
X0279528Y0284449D03*
X0202756Y0409449D03*
X0302165Y0332677D03*
X0286417Y0327756D03*
X0288059Y0241869D03*
X0240158Y0242126D03*
X0160433Y0409449D03*
X0217488Y0357695D03*
X0201772Y0076772D03*
X0216535Y0068898D03*
X0311024Y0281496D03*
Y0283465D03*
Y0285433D03*
X0331693Y0269685D03*
X0343504D03*
X0357185Y0272736D03*
X0290158Y011063D03*
X0285039D03*
X027874D03*
X0272835D03*
X0191614Y0024476D03*
X0627559Y0295276D03*
X0612992Y0276772D03*
X0271654Y0362205D03*
X0101181Y0110433D03*
X011811Y0184055D03*
Y0237205D03*
X0120079Y0200787D03*
Y0253937D03*
X0163957Y035748D03*
X0181727D03*
X0199803Y0357283D03*
X0288059Y0246457D03*
X025889D03*
X0229035Y0246555D03*
X0354331Y0171291D03*
X0360236D03*
X0268437Y0241831D03*
X0268701Y0246457D03*
X0354331Y0141732D03*
X0360236D03*
Y0151575D03*
X0354331D03*
Y0161417D03*
X0360236D03*
X0354331Y0181102D03*
X0360236D03*
X0354331Y0190945D03*
X0360236D03*
Y0200787D03*
X0354331D03*
X0167484Y0198906D03*
X0278248Y0241831D03*
X0248819D03*
X023002Y024187D03*
X0278543Y0246457D03*
X0239173D03*
X024941D03*
X0397899Y0165616D03*
X0401575Y0168307D03*
X0401533Y0172321D03*
X0171884Y0149606D03*
X0167184D03*
X0697884Y0183071D03*
X0231496Y0093307D03*
X0241339D03*
X0251575D03*
X0290551Y0093701D03*
X0266535Y011063D03*
X0261024D03*
X0251181Y0110591D03*
X0240945Y011063D03*
X0231102D03*
X0172184Y0168571D03*
X0167084D03*
X0636221Y0295276D03*
X0645084Y0246263D03*
Y0253543D03*
X0645276Y026063D03*
X0645182Y0267323D03*
X0645084Y0274016D03*
X065878Y0152931D03*
X0659449Y0167323D03*
Y0161024D03*
Y0177559D03*
Y0172047D03*
X0349705Y0064173D03*
X0171484Y0159506D03*
X0260668Y009319D03*
X0171884Y0179206D03*
X0167584Y0189106D03*
X0167184Y0179206D03*
Y0139906D03*
X0167084Y0159506D03*
X0171684Y0139906D03*
X0172184Y0198906D03*
Y0189006D03*
X0287828Y002496D03*
X0295747Y0025197D03*
X0244706Y0024259D03*
X0263687Y0024791D03*
X0279999Y0025197D03*
X0254606Y0024484D03*
X0309744Y0025197D03*
X0203484Y0024606D03*
X0230984D03*
X0662884Y0137206D03*
X0349853Y0068206D03*
X0669478Y018309D03*
X0669984Y0188106D03*
X0694984Y0209506D03*
X0660784Y0217606D03*
X0639584Y0211106D03*
X0604884Y0217106D03*
X0600394Y0243021D03*
X0627484Y0239106D03*
X0052689Y0079006D03*
X0052789Y0102806D03*
X0052689Y0131406D03*
X0052589Y0155106D03*
X0052689Y0183906D03*
Y0236506D03*
X0052601Y0259389D03*
M02*